G04 ================== begin FILE IDENTIFICATION RECORD ==================*
G04 Layout Name:  9052_F0T_PDB_Converter_Brick_F_V03_1208_1600.brd*
G04 Film Name:    gnd*
G04 File Format:  Gerber RS274X*
G04 File Origin:  Cadence Allegro 17.2-S081*
G04 Origin Date:  Wed Dec 21 09:54:58 2022*
G04 *
G04 Layer:  DRAWING FORMAT/TITLE_BLOCK_A*
G04 Layer:  PIN/SPECIAL_DRILL*
G04 Layer:  DRAWING FORMAT/TITLE_BLOCK*
G04 Layer:  VIA CLASS/GND*
G04 Layer:  PIN/GND*
G04 Layer:  MANUFACTURING/PHOTOPLOT_OUTLINE*
G04 Layer:  ETCH/GND*
G04 Layer:  DRAWING FORMAT/TITLE_DATA_GND*
G04 *
G04 Offset:    (0.00 0.00)*
G04 Mirror:    No*
G04 Mode:      Negative*
G04 Rotation:  0*
G04 FullContactRelief:  No*
G04 UndefLineWidth:     6.00*
G04 ================== end FILE IDENTIFICATION RECORD ====================*
%FSLAX25Y25*MOIN*%
%IR0*IPPOS*OFA0.00000B0.00000*MIA0B0*SFA1.00000B1.00000*%
%ADD20C,.03*%
%AMMACRO12*
4,1,41,.45275,-.05906,
.463006,-.058163,
.47295,-.055498,
.48228,-.051147,
.490713,-.045243,
.497993,-.037963,
.503897,-.02953,
.508248,-.0202,
.510913,-.010256,
.51181,0.0,
.510913,.010256,
.508248,.0202,
.503897,.02953,
.497993,.037963,
.490713,.045243,
.48228,.051147,
.47295,.055498,
.463006,.058163,
.45275,.05906,
.33464,.05906,
-.4082,.09829,
-.425347,.097699,
-.442131,.09414,
-.458041,.08772,
-.472595,.078635,
-.485351,.06716,
-.49592,.053645,
-.503981,.0385,
-.509291,.022185,
-.511686,.005196,
-.511095,-.011951,
-.507536,-.028734,
-.501116,-.044645,
-.492031,-.059199,
-.480557,-.071954,
-.467041,-.082523,
-.451896,-.090585,
-.435582,-.095894,
-.418593,-.09829,
-.4082,-.09829,
.33464,-.05906,
.45275,-.05906,
0.0*
%
%ADD12MACRO12*%
%ADD35C,.06*%
%ADD16C,.061*%
%ADD28C,.062*%
%ADD25C,.026*%
%ADD17C,.054*%
%AMMACRO27*
4,1,36,.0025,0.0,
.002462,.000434,
.002349,.000855,
.002165,.00125,
.001915,.001607,
.001607,.001915,
.00125,.002165,
.000855,.002349,
.000434,.002462,
0.0,.0025,
-.000434,.002462,
-.000855,.002349,
-.00125,.002165,
-.001607,.001915,
-.001915,.001607,
-.002165,.00125,
-.002349,.000855,
-.002462,.000434,
-.0025,0.0,
-.002462,-.000434,
-.002349,-.000855,
-.002165,-.00125,
-.001915,-.001607,
-.001607,-.001915,
-.00125,-.002165,
-.000855,-.002349,
-.000434,-.002462,
0.0,-.0025,
.000434,-.002462,
.000855,-.002349,
.00125,-.002165,
.001607,-.001915,
.001915,-.001607,
.002165,-.00125,
.002349,-.000855,
.002462,-.000434,
.0025,0.0,
180.*
%
%ADD27MACRO27*%
%AMMACRO23*
4,1,36,.0025,0.0,
.002462,.000434,
.002349,.000855,
.002165,.00125,
.001915,.001607,
.001607,.001915,
.00125,.002165,
.000855,.002349,
.000434,.002462,
0.0,.0025,
-.000434,.002462,
-.000855,.002349,
-.00125,.002165,
-.001607,.001915,
-.001915,.001607,
-.002165,.00125,
-.002349,.000855,
-.002462,.000434,
-.0025,0.0,
-.002462,-.000434,
-.002349,-.000855,
-.002165,-.00125,
-.001915,-.001607,
-.001607,-.001915,
-.00125,-.002165,
-.000855,-.002349,
-.000434,-.002462,
0.0,-.0025,
.000434,-.002462,
.000855,-.002349,
.00125,-.002165,
.001607,-.001915,
.001915,-.001607,
.002165,-.00125,
.002349,-.000855,
.002462,-.000434,
.0025,0.0,
270.*
%
%ADD23MACRO23*%
%ADD33C,.083*%
%ADD30C,.056*%
%ADD43C,.066*%
%ADD38C,.06015*%
%ADD40C,.087*%
%AMMACRO37*
4,1,36,0.0,.019,
-.003299,.018711,
-.006498,.017854,
-.0095,.016454,
-.012213,.014555,
-.014555,.012213,
-.016454,.0095,
-.017854,.006498,
-.018711,.003299,
-.019,0.0,
-.018711,-.003299,
-.017854,-.006498,
-.016454,-.0095,
-.014555,-.012213,
-.012213,-.014555,
-.0095,-.016454,
-.006498,-.017854,
-.003299,-.018711,
0.0,-.019,
.003299,-.018711,
.006498,-.017854,
.0095,-.016454,
.012213,-.014555,
.014555,-.012213,
.016454,-.0095,
.017854,-.006498,
.018711,-.003299,
.019,0.0,
.018711,.003299,
.017854,.006498,
.016454,.0095,
.014555,.012213,
.012213,.014555,
.0095,.016454,
.006498,.017854,
.003299,.018711,
0.0,.019,
0.0*
%
%ADD37MACRO37*%
%AMMACRO26*
4,1,16,.04271,.02503,
.046408,.017233,
.048695,.008913,
.049503,.000322,
.048807,-.008279,
.046628,-.016629,
.043032,-.024473,
.04271,-.02503,
.0478,-.03012,
.052304,-.021362,
.055219,-.011955,
.056456,-.002185,
.055978,.007652,
.053799,.017256,
.049985,.026336,
.0478,.03012,
.04271,.02503,
270.*
4,1,16,.02503,-.04271,
.017233,-.046408,
.008913,-.048695,
.000322,-.049503,
-.008279,-.048807,
-.016629,-.046628,
-.024473,-.043032,
-.02503,-.04271,
-.03012,-.0478,
-.021362,-.052304,
-.011955,-.055219,
-.002185,-.056456,
.007652,-.055978,
.017256,-.053799,
.026336,-.049985,
.03012,-.0478,
.02503,-.04271,
270.*
4,1,16,-.04271,-.02503,
-.046408,-.017233,
-.048695,-.008913,
-.049503,-.000322,
-.048807,.008279,
-.046628,.016629,
-.043032,.024473,
-.04271,.02503,
-.0478,.03012,
-.052304,.021362,
-.055219,.011955,
-.056456,.002185,
-.055978,-.007652,
-.053799,-.017256,
-.049985,-.026336,
-.0478,-.03012,
-.04271,-.02503,
270.*
4,1,16,-.02503,.04271,
-.017233,.046408,
-.008913,.048695,
-.000322,.049503,
.008279,.048807,
.016629,.046628,
.024473,.043032,
.02503,.04271,
.03012,.0478,
.021362,.052304,
.011955,.055219,
.002185,.056456,
-.007652,.055978,
-.017256,.053799,
-.026336,.049985,
-.03012,.0478,
-.02503,.04271,
270.*
%
%ADD26MACRO26*%
%AMMACRO44*
4,1,16,.02657,.01597,
.02894,.011114,
.03043,.005919,
.030995,.000545,
.030619,-.004845,
.029313,-.010088,
.027115,-.015025,
.02657,-.01597,
.03164,-.02104,
.034813,-.015226,
.036928,-.00895,
.037921,-.002401,
.037762,.00422,
.036455,.010713,
.034041,.016881,
.03164,.02104,
.02657,.01597,
90.*
4,1,16,.01597,-.02657,
.011114,-.02894,
.005919,-.03043,
.000545,-.030995,
-.004845,-.030619,
-.010088,-.029313,
-.015025,-.027115,
-.01597,-.02657,
-.02104,-.03164,
-.015226,-.034813,
-.00895,-.036928,
-.002401,-.037921,
.00422,-.037762,
.010713,-.036455,
.016881,-.034041,
.02104,-.03164,
.01597,-.02657,
90.*
4,1,16,-.02657,-.01597,
-.02894,-.011114,
-.03043,-.005919,
-.030995,-.000545,
-.030619,.004845,
-.029313,.010088,
-.027115,.015025,
-.02657,.01597,
-.03164,.02104,
-.034813,.015226,
-.036928,.00895,
-.037921,.002401,
-.037762,-.00422,
-.036455,-.010713,
-.034041,-.016881,
-.03164,-.02104,
-.02657,-.01597,
90.*
4,1,16,-.01597,.02657,
-.011114,.02894,
-.005919,.03043,
-.000545,.030995,
.004845,.030619,
.010088,.029313,
.015025,.027115,
.01597,.02657,
.02104,.03164,
.015226,.034813,
.00895,.036928,
.002401,.037921,
-.00422,.037762,
-.010713,.036455,
-.016881,.034041,
-.02104,.03164,
-.01597,.02657,
90.*
%
%ADD44MACRO44*%
%AMMACRO29*
4,1,16,.02511,.01451,
.027248,.009929,
.028558,.005047,
.029001,.000011,
.028562,-.005025,
.027256,-.009909,
.025121,-.014491,
.02511,-.01451,
.0302,-.01959,
.033143,-.014048,
.035079,-.00808,
.035949,-.001865,
.035727,.004405,
.034419,.010542,
.032065,.016359,
.0302,.01959,
.02511,.01451,
0.0*
4,1,16,.01451,-.02511,
.009929,-.027248,
.005047,-.028558,
.000011,-.029001,
-.005025,-.028562,
-.009909,-.027256,
-.014491,-.025121,
-.01451,-.02511,
-.01959,-.0302,
-.014048,-.033143,
-.00808,-.035079,
-.001865,-.035949,
.004405,-.035727,
.010542,-.034419,
.016359,-.032065,
.01959,-.0302,
.01451,-.02511,
0.0*
4,1,16,-.02511,-.01451,
-.027248,-.009929,
-.028558,-.005047,
-.029001,-.000011,
-.028562,.005025,
-.027256,.009909,
-.025121,.014491,
-.02511,.01451,
-.0302,.01959,
-.033143,.014048,
-.035079,.00808,
-.035949,.001865,
-.035727,-.004405,
-.034419,-.010542,
-.032065,-.016359,
-.0302,-.01959,
-.02511,-.01451,
0.0*
4,1,16,-.01451,.02511,
-.009929,.027248,
-.005047,.028558,
-.000011,.029001,
.005025,.028562,
.009909,.027256,
.014491,.025121,
.01451,.02511,
.01959,.0302,
.014048,.033143,
.00808,.035079,
.001865,.035949,
-.004405,.035727,
-.010542,.034419,
-.016359,.032065,
-.01959,.0302,
-.01451,.02511,
0.0*
%
%ADD29MACRO29*%
%AMMACRO46*
4,1,15,.03682,.01914,
.039584,.012455,
.041146,.005393,
.041457,-.001834,
.040509,-.009005,
.03833,-.015903,
.03682,-.01914,
.04197,-.0243,
.045552,-.016643,
.04775,-.00848,
.048497,-.000059,
.047771,.008363,
.045593,.016531,
.042029,.024197,
.04197,.0243,
.03682,.01914,
90.*
4,1,15,.01914,-.03682,
.012455,-.039584,
.005393,-.041146,
-.001834,-.041457,
-.009005,-.040509,
-.015903,-.03833,
-.01914,-.03682,
-.0243,-.04197,
-.016643,-.045552,
-.00848,-.04775,
-.000059,-.048497,
.008363,-.047771,
.016531,-.045593,
.024197,-.042029,
.0243,-.04197,
.01914,-.03682,
90.*
4,1,15,-.03682,-.01914,
-.039584,-.012455,
-.041146,-.005393,
-.041457,.001834,
-.040509,.009005,
-.03833,.015903,
-.03682,.01914,
-.04197,.0243,
-.045552,.016643,
-.04775,.00848,
-.048497,.000059,
-.047771,-.008363,
-.045593,-.016531,
-.042029,-.024197,
-.04197,-.0243,
-.03682,-.01914,
90.*
4,1,15,-.01914,.03682,
-.012455,.039584,
-.005393,.041146,
.001834,.041457,
.009005,.040509,
.015903,.03833,
.01914,.03682,
.0243,.04197,
.016643,.045552,
.00848,.04775,
.000059,.048497,
-.008363,.047771,
-.016531,.045593,
-.024197,.042029,
-.0243,.04197,
-.01914,.03682,
90.*
%
%ADD46MACRO46*%
%AMMACRO45*
4,1,15,-.03682,.01914,
-.039584,.012455,
-.041146,.005393,
-.041457,-.001834,
-.040509,-.009005,
-.03833,-.015903,
-.03682,-.01914,
-.04197,-.0243,
-.045552,-.016643,
-.04775,-.00848,
-.048497,-.000059,
-.047771,.008363,
-.045593,.016531,
-.042029,.024197,
-.04197,.0243,
-.03682,.01914,
90.*
4,1,15,-.01914,-.03682,
-.012455,-.039584,
-.005393,-.041146,
.001834,-.041457,
.009005,-.040509,
.015903,-.03833,
.01914,-.03682,
.0243,-.04197,
.016643,-.045552,
.00848,-.04775,
.000059,-.048497,
-.008363,-.047771,
-.016531,-.045593,
-.024197,-.042029,
-.0243,-.04197,
-.01914,-.03682,
90.*
4,1,15,.03682,-.01914,
.039584,-.012455,
.041146,-.005393,
.041457,.001834,
.040509,.009005,
.03833,.015903,
.03682,.01914,
.04197,.0243,
.045552,.016643,
.04775,.00848,
.048497,.000059,
.047771,-.008363,
.045593,-.016531,
.042029,-.024197,
.04197,-.0243,
.03682,-.01914,
90.*
4,1,15,.01914,.03682,
.012455,.039584,
.005393,.041146,
-.001834,.041457,
-.009005,.040509,
-.015903,.03833,
-.01914,.03682,
-.0243,.04197,
-.016643,.045552,
-.00848,.04775,
-.000059,.048497,
.008363,.047771,
.016531,.045593,
.024197,.042029,
.0243,.04197,
.01914,.03682,
90.*
%
%ADD45MACRO45*%
%ADD36C,.103*%
%AMMACRO13*
4,1,36,0.0,.005,
.000868,.004924,
.00171,.004698,
.0025,.00433,
.003214,.00383,
.00383,.003214,
.00433,.0025,
.004698,.00171,
.004924,.000868,
.005,0.0,
.004924,-.000868,
.004698,-.00171,
.00433,-.0025,
.00383,-.003214,
.003214,-.00383,
.0025,-.00433,
.00171,-.004698,
.000868,-.004924,
0.0,-.005,
-.000868,-.004924,
-.00171,-.004698,
-.0025,-.00433,
-.003214,-.00383,
-.00383,-.003214,
-.00433,-.0025,
-.004698,-.00171,
-.004924,-.000868,
-.005,0.0,
-.004924,.000868,
-.004698,.00171,
-.00433,.0025,
-.00383,.003214,
-.003214,.00383,
-.0025,.00433,
-.00171,.004698,
-.000868,.004924,
0.0,.005,
270.*
%
%ADD13MACRO13*%
%ADD11C,.125*%
%ADD14C,.117*%
%ADD24C,.155*%
%ADD21C,.237*%
%ADD32C,.256*%
%AMMACRO22*
4,1,36,.0025,0.0,
.002462,.000434,
.002349,.000855,
.002165,.00125,
.001915,.001607,
.001607,.001915,
.00125,.002165,
.000855,.002349,
.000434,.002462,
0.0,.0025,
-.000434,.002462,
-.000855,.002349,
-.00125,.002165,
-.001607,.001915,
-.001915,.001607,
-.002165,.00125,
-.002349,.000855,
-.002462,.000434,
-.0025,0.0,
-.002462,-.000434,
-.002349,-.000855,
-.002165,-.00125,
-.001915,-.001607,
-.001607,-.001915,
-.00125,-.002165,
-.000855,-.002349,
-.000434,-.002462,
0.0,-.0025,
.000434,-.002462,
.000855,-.002349,
.00125,-.002165,
.001607,-.001915,
.001915,-.001607,
.002165,-.00125,
.002349,-.000855,
.002462,-.000434,
.0025,0.0,
90.*
%
%ADD22MACRO22*%
%ADD19C,.186*%
%ADD48C,.187*%
%AMMACRO42*
4,1,36,0.0,.019,
-.003299,.018711,
-.006498,.017854,
-.0095,.016454,
-.012213,.014555,
-.014555,.012213,
-.016454,.0095,
-.017854,.006498,
-.018711,.003299,
-.019,0.0,
-.018711,-.003299,
-.017854,-.006498,
-.016454,-.0095,
-.014555,-.012213,
-.012213,-.014555,
-.0095,-.016454,
-.006498,-.017854,
-.003299,-.018711,
0.0,-.019,
.003299,-.018711,
.006498,-.017854,
.0095,-.016454,
.012213,-.014555,
.014555,-.012213,
.016454,-.0095,
.017854,-.006498,
.018711,-.003299,
.019,0.0,
.018711,.003299,
.017854,.006498,
.016454,.0095,
.014555,.012213,
.012213,.014555,
.0095,.016454,
.006498,.017854,
.003299,.018711,
0.0,.019,
270.*
%
%ADD42MACRO42*%
%AMMACRO10*
4,1,36,.0025,0.0,
.002462,.000434,
.002349,.000855,
.002165,.00125,
.001915,.001607,
.001607,.001915,
.00125,.002165,
.000855,.002349,
.000434,.002462,
0.0,.0025,
-.000434,.002462,
-.000855,.002349,
-.00125,.002165,
-.001607,.001915,
-.001915,.001607,
-.002165,.00125,
-.002349,.000855,
-.002462,.000434,
-.0025,0.0,
-.002462,-.000434,
-.002349,-.000855,
-.002165,-.00125,
-.001915,-.001607,
-.001607,-.001915,
-.00125,-.002165,
-.000855,-.002349,
-.000434,-.002462,
0.0,-.0025,
.000434,-.002462,
.000855,-.002349,
.00125,-.002165,
.001607,-.001915,
.001915,-.001607,
.002165,-.00125,
.002349,-.000855,
.002462,-.000434,
.0025,0.0,
0.0*
%
%ADD10MACRO10*%
%AMMACRO18*
4,1,15,.02217,.01156,
.023841,.007535,
.024787,.00328,
.02498,-.001074,
.024414,-.005395,
.023106,-.009553,
.02217,-.01156,
.0273,-.01669,
.029783,-.011696,
.031362,-.006346,
.031987,-.000804,
.031641,.004763,
.030333,.010185,
.028104,.015297,
.0273,.01669,
.02217,.01156,
270.*
4,1,15,.01156,-.02217,
.007535,-.023841,
.00328,-.024787,
-.001074,-.02498,
-.005395,-.024414,
-.009553,-.023106,
-.01156,-.02217,
-.01669,-.0273,
-.011696,-.029783,
-.006346,-.031362,
-.000804,-.031987,
.004763,-.031641,
.010185,-.030333,
.015297,-.028104,
.01669,-.0273,
.01156,-.02217,
270.*
4,1,15,-.02217,-.01156,
-.023841,-.007535,
-.024787,-.00328,
-.02498,.001074,
-.024414,.005395,
-.023106,.009553,
-.02217,.01156,
-.0273,.01669,
-.029783,.011696,
-.031362,.006346,
-.031987,.000804,
-.031641,-.004763,
-.030333,-.010185,
-.028104,-.015297,
-.0273,-.01669,
-.02217,-.01156,
270.*
4,1,15,-.01156,.02217,
-.007535,.023841,
-.00328,.024787,
.001074,.02498,
.005395,.024414,
.009553,.023106,
.01156,.02217,
.01669,.0273,
.011696,.029783,
.006346,.031362,
.000804,.031987,
-.004763,.031641,
-.010185,.030333,
-.015297,.028104,
-.01669,.0273,
-.01156,.02217,
270.*
%
%ADD18MACRO18*%
%AMMACRO34*
4,1,15,.02438,.01377,
.026401,.009327,
.027619,.004601,
.027999,-.000265,
.027527,-.005123,
.02622,-.009825,
.02438,-.01377,
.02948,-.01887,
.032309,-.013464,
.034156,-.007649,
.034965,-.001602,
.034712,.004494,
.033405,.010454,
.031082,.016095,
.02948,.01887,
.02438,.01377,
270.*
4,1,15,.01377,-.02438,
.009327,-.026401,
.004601,-.027619,
-.000265,-.027999,
-.005123,-.027527,
-.009825,-.02622,
-.01377,-.02438,
-.01887,-.02948,
-.013464,-.032309,
-.007649,-.034156,
-.001602,-.034965,
.004494,-.034712,
.010454,-.033405,
.016095,-.031082,
.01887,-.02948,
.01377,-.02438,
270.*
4,1,15,-.02438,-.01377,
-.026401,-.009327,
-.027619,-.004601,
-.027999,.000265,
-.027527,.005123,
-.02622,.009825,
-.02438,.01377,
-.02948,.01887,
-.032309,.013464,
-.034156,.007649,
-.034965,.001602,
-.034712,-.004494,
-.033405,-.010454,
-.031082,-.016095,
-.02948,-.01887,
-.02438,-.01377,
270.*
4,1,15,-.01377,.02438,
-.009327,.026401,
-.004601,.027619,
.000265,.027999,
.005123,.027527,
.009825,.02622,
.01377,.02438,
.01887,.02948,
.013464,.032309,
.007649,.034156,
.001602,.034965,
-.004494,.034712,
-.010454,.033405,
-.016095,.031082,
-.01887,.02948,
-.01377,.02438,
270.*
%
%ADD34MACRO34*%
%AMMACRO15*
4,1,15,.02475,.01414,
.026829,.009627,
.028094,.004822,
.028504,-.000129,
.028049,-.005077,
.026741,-.009871,
.02475,-.01414,
.02984,-.01923,
.032726,-.013756,
.034617,-.007864,
.035457,-.001734,
.03522,.00445,
.033912,.010498,
.031574,.016227,
.02984,.01923,
.02475,.01414,
270.*
4,1,15,.01414,-.02475,
.009627,-.026829,
.004822,-.028094,
-.000129,-.028504,
-.005077,-.028049,
-.009871,-.026741,
-.01414,-.02475,
-.01923,-.02984,
-.013756,-.032726,
-.007864,-.034617,
-.001734,-.035457,
.00445,-.03522,
.010498,-.033912,
.016227,-.031574,
.01923,-.02984,
.01414,-.02475,
270.*
4,1,15,-.02475,-.01414,
-.026829,-.009627,
-.028094,-.004822,
-.028504,.000129,
-.028049,.005077,
-.026741,.009871,
-.02475,.01414,
-.02984,.01923,
-.032726,.013756,
-.034617,.007864,
-.035457,.001734,
-.03522,-.00445,
-.033912,-.010498,
-.031574,-.016227,
-.02984,-.01923,
-.02475,-.01414,
270.*
4,1,15,-.01414,.02475,
-.009627,.026829,
-.004822,.028094,
.000129,.028504,
.005077,.028049,
.009871,.026741,
.01414,.02475,
.01923,.02984,
.013756,.032726,
.007864,.034617,
.001734,.035457,
-.00445,.03522,
-.010498,.033912,
-.016227,.031574,
-.01923,.02984,
-.01414,.02475,
270.*
%
%ADD15MACRO15*%
%AMMACRO47*
4,1,18,.10783,.07955,
.120006,.059617,
.128535,.037873,
.133159,.014977,
.133736,-.008373,
.130251,-.031469,
.122807,-.053609,
.111633,-.074119,
.10783,-.07955,
.11284,-.08455,
.125808,-.063671,
.134953,-.040857,
.139997,-.016802,
.140788,.007763,
.137301,.032093,
.129642,.055447,
.118045,.077117,
.11284,.08455,
.10783,.07955,
270.*
4,1,18,.07955,-.10783,
.059617,-.120006,
.037873,-.128535,
.014977,-.133159,
-.008373,-.133736,
-.031469,-.130251,
-.053609,-.122807,
-.074119,-.111633,
-.07955,-.10783,
-.08455,-.11284,
-.063671,-.125808,
-.040857,-.134953,
-.016802,-.139997,
.007763,-.140788,
.032093,-.137301,
.055447,-.129642,
.077117,-.118045,
.08455,-.11284,
.07955,-.10783,
270.*
4,1,18,-.10783,-.07955,
-.120006,-.059617,
-.128535,-.037873,
-.133159,-.014977,
-.133736,.008373,
-.130251,.031469,
-.122807,.053609,
-.111633,.074119,
-.10783,.07955,
-.11284,.08455,
-.125808,.063671,
-.134953,.040857,
-.139997,.016802,
-.140788,-.007763,
-.137301,-.032093,
-.129642,-.055447,
-.118045,-.077117,
-.11284,-.08455,
-.10783,-.07955,
270.*
4,1,18,-.07955,.10783,
-.059617,.120006,
-.037873,.128535,
-.014977,.133159,
.008373,.133736,
.031469,.130251,
.053609,.122807,
.074119,.111633,
.07955,.10783,
.08455,.11284,
.063671,.125808,
.040857,.134953,
.016802,.139997,
-.007763,.140788,
-.032093,.137301,
-.055447,.129642,
-.077117,.118045,
-.08455,.11284,
-.07955,.10783,
270.*
%
%ADD47MACRO47*%
%AMMACRO39*
4,1,15,.03682,.01914,
.039584,.012455,
.041146,.005393,
.041457,-.001834,
.040509,-.009005,
.03833,-.015903,
.03682,-.01914,
.04197,-.0243,
.045552,-.016643,
.04775,-.00848,
.048497,-.000059,
.047771,.008363,
.045593,.016531,
.042029,.024197,
.04197,.0243,
.03682,.01914,
270.*
4,1,15,.01914,-.03682,
.012455,-.039584,
.005393,-.041146,
-.001834,-.041457,
-.009005,-.040509,
-.015903,-.03833,
-.01914,-.03682,
-.0243,-.04197,
-.016643,-.045552,
-.00848,-.04775,
-.000059,-.048497,
.008363,-.047771,
.016531,-.045593,
.024197,-.042029,
.0243,-.04197,
.01914,-.03682,
270.*
4,1,15,-.03682,-.01914,
-.039584,-.012455,
-.041146,-.005393,
-.041457,.001834,
-.040509,.009005,
-.03833,.015903,
-.03682,.01914,
-.04197,.0243,
-.045552,.016643,
-.04775,.00848,
-.048497,.000059,
-.047771,-.008363,
-.045593,-.016531,
-.042029,-.024197,
-.04197,-.0243,
-.03682,-.01914,
270.*
4,1,15,-.01914,.03682,
-.012455,.039584,
-.005393,.041146,
.001834,.041457,
.009005,.040509,
.015903,.03833,
.01914,.03682,
.0243,.04197,
.016643,.045552,
.00848,.04775,
.000059,.048497,
-.008363,.047771,
-.016531,.045593,
-.024197,.042029,
-.0243,.04197,
-.01914,.03682,
270.*
%
%ADD39MACRO39*%
%AMMACRO31*
4,1,17,.03273,.02212,
.036074,.0161,
.038322,.009592,
.039405,.002791,
.039291,-.004094,
.037983,-.010854,
.035521,-.017285,
.03273,-.02212,
.03775,-.02715,
.041891,-.020182,
.044759,-.012601,
.046267,-.004638,
.04637,.003467,
.045063,.011466,
.042388,.019117,
.038424,.026188,
.03775,.02715,
.03273,.02212,
270.*
4,1,17,.02212,-.03273,
.0161,-.036074,
.009592,-.038322,
.002791,-.039405,
-.004094,-.039291,
-.010854,-.037983,
-.017285,-.035521,
-.02212,-.03273,
-.02715,-.03775,
-.020182,-.041891,
-.012601,-.044759,
-.004638,-.046267,
.003467,-.04637,
.011466,-.045063,
.019117,-.042388,
.026188,-.038424,
.02715,-.03775,
.02212,-.03273,
270.*
4,1,17,-.03273,-.02212,
-.036074,-.0161,
-.038322,-.009592,
-.039405,-.002791,
-.039291,.004094,
-.037983,.010854,
-.035521,.017285,
-.03273,.02212,
-.03775,.02715,
-.041891,.020182,
-.044759,.012601,
-.046267,.004638,
-.04637,-.003467,
-.045063,-.011466,
-.042388,-.019117,
-.038424,-.026188,
-.03775,-.02715,
-.03273,-.02212,
270.*
4,1,17,-.02212,.03273,
-.0161,.036074,
-.009592,.038322,
-.002791,.039405,
.004094,.039291,
.010854,.037983,
.017285,.035521,
.02212,.03273,
.02715,.03775,
.020182,.041891,
.012601,.044759,
.004638,.046267,
-.003467,.04637,
-.011466,.045063,
-.019117,.042388,
-.026188,.038424,
-.02715,.03775,
-.02212,.03273,
270.*
%
%ADD31MACRO31*%
%AMMACRO41*
4,1,15,-.03682,.01914,
-.039584,.012455,
-.041146,.005393,
-.041457,-.001834,
-.040509,-.009005,
-.03833,-.015903,
-.03682,-.01914,
-.04197,-.0243,
-.045552,-.016643,
-.04775,-.00848,
-.048497,-.000059,
-.047771,.008363,
-.045593,.016531,
-.042029,.024197,
-.04197,.0243,
-.03682,.01914,
270.*
4,1,15,-.01914,-.03682,
-.012455,-.039584,
-.005393,-.041146,
.001834,-.041457,
.009005,-.040509,
.015903,-.03833,
.01914,-.03682,
.0243,-.04197,
.016643,-.045552,
.00848,-.04775,
.000059,-.048497,
-.008363,-.047771,
-.016531,-.045593,
-.024197,-.042029,
-.0243,-.04197,
-.01914,-.03682,
270.*
4,1,15,.03682,-.01914,
.039584,-.012455,
.041146,-.005393,
.041457,.001834,
.040509,.009005,
.03833,.015903,
.03682,.01914,
.04197,.0243,
.045552,.016643,
.04775,.00848,
.048497,.000059,
.047771,-.008363,
.045593,-.016531,
.042029,-.024197,
.04197,-.0243,
.03682,-.01914,
270.*
4,1,15,.01914,.03682,
.012455,.039584,
.005393,.041146,
-.001834,.041457,
-.009005,.040509,
-.015903,.03833,
-.01914,.03682,
-.0243,.04197,
-.016643,.045552,
-.00848,.04775,
-.000059,.048497,
.008363,.047771,
.016531,.045593,
.024197,.042029,
.0243,.04197,
.01914,.03682,
270.*
%
%ADD41MACRO41*%
%ADD49C,.02*%
%ADD50C,.006*%
%ADD56C,.07006*%
%ADD59C,.11022*%
%ADD60C,.10006*%
%ADD57C,.11006*%
%ADD55C,.11206*%
%ADD58C,.14306*%
%ADD52C,.12707*%
%ADD53C,.16506*%
%ADD54C,.19606*%
%ADD51C,.28606*%
%ADD61C,.32598*%
G75*
%LPD*%
G75*
G36*
G01X-297025Y-1013390D02*
X3691357D01*
Y1828909D01*
X-297025D01*
Y-1013390D01*
G37*
%LPC*%
G75*
G36*
G01X1048555Y576740D02*
X1049868D01*
Y576736D01*
X1271654D01*
G02X1289335Y559055I0J-17681D01*
G01Y19685D01*
G02X1271654Y2004I-17681J0D01*
G01X19685D01*
G02X2004Y19685I0J17681D01*
G01Y63268D01*
G02X11811Y73075I9807J0D01*
G01X37796D01*
G03X41768Y77047I0J3973D01*
G01Y122323D01*
G03X37796Y126295I-3973J-1D01*
G01X11811D01*
G02X2004Y136102I0J9807D01*
G01Y445787D01*
G02X11811Y455594I9807J0D01*
G01X37795D01*
G03X41768Y459567I0J3973D01*
G01Y504843D01*
G03X37796Y508815I-3973J-1D01*
G01X11811D01*
G02X2004Y518622I0J9807D01*
G01Y559055D01*
G02X19685Y576736I17681J0D01*
G01X1048555D01*
Y576740D01*
G37*
G36*
G01X1283465Y654614D02*
G02X1289339Y648740I0J-5874D01*
G01Y594488D01*
G02X1283465Y588614I-5874J0D01*
G01X607874D01*
G02X602000Y594488I0J5874D01*
G01Y648740D01*
G02X607874Y654614I5874J0D01*
G01X1283465D01*
G37*
%LPD*%
G75*
G36*
G01X1174341Y186396D02*
G02X1175755Y186982I1414J-1413D01*
G01X1190755D01*
G02X1192169Y186396I0J-1999D01*
G01X1193769Y184796D01*
G02X1194355Y183382I-1413J-1414D01*
G01Y150882D01*
G02X1193769Y149468I-1999J0D01*
G01X1192369Y148068D01*
G02X1190955Y147482I-1414J1413D01*
G01X1175239D01*
G02X1173825Y148068I0J1999D01*
G01X1172841Y149052D01*
G02X1172255Y150466I1413J1414D01*
G01Y183482D01*
G02X1172841Y184896I1999J0D01*
G01X1174341Y186396D01*
G37*
G36*
G01X787338Y152253D02*
X787780D01*
X787869Y152303D01*
X787897Y152347D01*
G02X792559Y154918I4661J-2940D01*
G02X798070Y149408I1J-5510D01*
G02X795498Y144746I-5511J0D01*
G01X795454Y144718D01*
X795404Y144629D01*
Y144187D01*
X795454Y144098D01*
X795498Y144070D01*
G02X798070Y139408I-2939J-4662D01*
G02X795497Y134746I-5510J0D01*
G01X795453Y134718D01*
X795404Y134630D01*
Y134186D01*
X795453Y134098D01*
X795497Y134070D01*
G02X798070Y129408I-2937J-4662D01*
G02X795498Y124746I-5511J0D01*
G01X795454Y124718D01*
X795404Y124629D01*
Y124187D01*
X795454Y124098D01*
X795498Y124070D01*
G02X798070Y119408I-2939J-4662D01*
G02X792559Y113898I-5511J1D01*
G02X787897Y116469I-1J5511D01*
G01X787869Y116513D01*
X787780Y116563D01*
X787338D01*
X787249Y116513D01*
X787221Y116469D01*
G02X782559Y113898I-4661J2940D01*
G02X777048Y119408I-1J5510D01*
G02X779621Y124070I5510J0D01*
G01X779665Y124098D01*
X779714Y124186D01*
Y124630D01*
X779665Y124718D01*
X779621Y124746D01*
G02Y134070I2938J4662D01*
G01X779665Y134098D01*
X779714Y134186D01*
Y134630D01*
X779665Y134718D01*
X779621Y134746D01*
G02X777048Y139408I2937J4662D01*
G02X779620Y144070I5511J0D01*
G01X779664Y144098D01*
X779714Y144187D01*
Y144629D01*
X779664Y144718D01*
X779620Y144746D01*
G02X777048Y149408I2939J4662D01*
G02X782559Y154918I5511J-1D01*
G02X787221Y152347I1J-5511D01*
G01X787249Y152303D01*
X787338Y152253D01*
G37*
G36*
G01X752338D02*
X752780D01*
X752869Y152303D01*
X752897Y152347D01*
G02X757559Y154918I4661J-2940D01*
G02X763070Y149408I1J-5510D01*
G02X760497Y144746I-5510J0D01*
G01X760453Y144718D01*
X760404Y144630D01*
Y144186D01*
X760453Y144098D01*
X760497Y144070D01*
G02X763070Y139408I-2937J-4662D01*
G02X760498Y134746I-5511J0D01*
G01X760454Y134718D01*
X760404Y134629D01*
Y134187D01*
X760454Y134098D01*
X760498Y134070D01*
G02X763070Y129408I-2939J-4662D01*
G02X760497Y124746I-5510J0D01*
G01X760453Y124718D01*
X760404Y124630D01*
Y124186D01*
X760453Y124098D01*
X760497Y124070D01*
G02X763070Y119408I-2937J-4662D01*
G02X757559Y113898I-5511J1D01*
G02X752897Y116470I-1J5510D01*
G01X752869Y116514D01*
X752781Y116563D01*
X752337D01*
X752249Y116514D01*
X752221Y116470D01*
G02X747559Y113898I-4661J2938D01*
G02X742048Y119408I-1J5510D01*
G02X744621Y124070I5510J0D01*
G01X744665Y124098D01*
X744714Y124186D01*
Y124630D01*
X744665Y124718D01*
X744621Y124746D01*
G02Y134070I2938J4662D01*
G01X744665Y134098D01*
X744714Y134186D01*
Y134630D01*
X744665Y134718D01*
X744621Y134746D01*
G02Y144070I2938J4662D01*
G01X744665Y144098D01*
X744714Y144186D01*
Y144630D01*
X744665Y144718D01*
X744621Y144746D01*
G02X742048Y149408I2937J4662D01*
G02X747559Y154918I5511J-1D01*
G02X752221Y152347I1J-5511D01*
G01X752249Y152303D01*
X752338Y152253D01*
G37*
G36*
G01X717337D02*
X717781D01*
X717869Y152302D01*
X717897Y152346D01*
G02X722559Y154918I4661J-2938D01*
G02X728070Y149408I1J-5510D01*
G02X725497Y144746I-5510J0D01*
G01X725453Y144718D01*
X725404Y144630D01*
Y144186D01*
X725453Y144098D01*
X725497Y144070D01*
G02Y134746I-2938J-4662D01*
G01X725453Y134718D01*
X725404Y134630D01*
Y134186D01*
X725453Y134098D01*
X725497Y134070D01*
G02Y124746I-2938J-4662D01*
G01X725453Y124718D01*
X725404Y124630D01*
Y124186D01*
X725453Y124098D01*
X725497Y124070D01*
G02X728070Y119408I-2937J-4662D01*
G02X722559Y113898I-5511J1D01*
G02X717897Y116470I-1J5510D01*
G01X717869Y116514D01*
X717781Y116563D01*
X717337D01*
X717249Y116514D01*
X717221Y116470D01*
G02X712559Y113898I-4661J2938D01*
G02X707048Y119408I-1J5510D01*
G02X709621Y124070I5510J0D01*
G01X709665Y124098D01*
X709714Y124186D01*
Y124630D01*
X709665Y124718D01*
X709621Y124746D01*
G02Y134070I2938J4662D01*
G01X709665Y134098D01*
X709714Y134186D01*
Y134630D01*
X709665Y134718D01*
X709621Y134746D01*
G02Y144070I2938J4662D01*
G01X709665Y144098D01*
X709714Y144186D01*
Y144630D01*
X709665Y144718D01*
X709621Y144746D01*
G02X707048Y149408I2937J4662D01*
G02X712559Y154918I5511J-1D01*
G02X717221Y152346I1J-5510D01*
G01X717249Y152302D01*
X717337Y152253D01*
G37*
G36*
G01X476530Y162530D02*
X476974D01*
X477062Y162579D01*
X477090Y162623D01*
G02X481752Y165196I4662J-2937D01*
G02X487262Y159685I-1J-5511D01*
G02X484691Y155023I-5511J-1D01*
G01X484647Y154995D01*
X484597Y154906D01*
Y154464D01*
X484647Y154375D01*
X484691Y154347D01*
G02X487262Y149685I-2940J-4661D01*
G02X484690Y145023I-5510J-1D01*
G01X484646Y144995D01*
X484597Y144907D01*
Y144463D01*
X484646Y144375D01*
X484690Y144347D01*
G02X487262Y139685I-2938J-4661D01*
G02X484691Y135023I-5511J-1D01*
G01X484647Y134995D01*
X484597Y134906D01*
Y134464D01*
X484647Y134375D01*
X484691Y134347D01*
G02X487262Y129685I-2940J-4661D01*
G02X481752Y124174I-5510J-1D01*
G02X477090Y126746I0J5511D01*
G01X477062Y126790D01*
X476973Y126840D01*
X476531D01*
X476442Y126790D01*
X476414Y126746D01*
G02X471752Y124174I-4662J2939D01*
G02X466242Y129685I1J5511D01*
G02X468814Y134347I5510J1D01*
G01X468858Y134375D01*
X468907Y134463D01*
Y134907D01*
X468858Y134995D01*
X468814Y135023D01*
G02Y144347I2938J4662D01*
G01X468858Y144375D01*
X468907Y144463D01*
Y144907D01*
X468858Y144995D01*
X468814Y145023D01*
G02Y154347I2938J4662D01*
G01X468858Y154375D01*
X468907Y154463D01*
Y154907D01*
X468858Y154995D01*
X468814Y155023D01*
G02X466242Y159685I2938J4661D01*
G02X471752Y165196I5510J1D01*
G02X476414Y162623I0J-5510D01*
G01X476442Y162579D01*
X476530Y162530D01*
G37*
G36*
G01X406530D02*
X406974D01*
X407062Y162579D01*
X407090Y162623D01*
G02X411752Y165196I4662J-2937D01*
G02X417262Y159685I-1J-5511D01*
G02X414690Y155023I-5510J-1D01*
G01X414646Y154995D01*
X414597Y154907D01*
Y154463D01*
X414646Y154375D01*
X414690Y154347D01*
G02Y145023I-2938J-4662D01*
G01X414646Y144995D01*
X414597Y144907D01*
Y144463D01*
X414646Y144375D01*
X414690Y144347D01*
G02Y135023I-2938J-4662D01*
G01X414646Y134995D01*
X414597Y134907D01*
Y134463D01*
X414646Y134375D01*
X414690Y134347D01*
G02X417262Y129685I-2938J-4661D01*
G02X411752Y124174I-5510J-1D01*
G02X407090Y126747I0J5510D01*
G01X407062Y126791D01*
X406974Y126840D01*
X406530D01*
X406442Y126791D01*
X406414Y126747D01*
G02X401752Y124174I-4662J2937D01*
G02X396242Y129685I1J5511D01*
G02X398814Y134347I5510J1D01*
G01X398858Y134375D01*
X398907Y134463D01*
Y134907D01*
X398858Y134995D01*
X398814Y135023D01*
G02Y144347I2938J4662D01*
G01X398858Y144375D01*
X398907Y144463D01*
Y144907D01*
X398858Y144995D01*
X398814Y145023D01*
G02Y154347I2938J4662D01*
G01X398858Y154375D01*
X398907Y154463D01*
Y154907D01*
X398858Y154995D01*
X398814Y155023D01*
G02X396242Y159685I2938J4661D01*
G02X401752Y165196I5510J1D01*
G02X406414Y162623I0J-5510D01*
G01X406442Y162579D01*
X406530Y162530D01*
G37*
G36*
G01X441530D02*
X441974D01*
X442062Y162579D01*
X442090Y162623D01*
G02X446752Y165196I4662J-2937D01*
G02X452262Y159685I-1J-5511D01*
G02X449690Y155023I-5510J-1D01*
G01X449646Y154995D01*
X449597Y154907D01*
Y154463D01*
X449646Y154375D01*
X449690Y154347D01*
G02Y145023I-2938J-4662D01*
G01X449646Y144995D01*
X449597Y144907D01*
Y144463D01*
X449646Y144375D01*
X449690Y144347D01*
G02Y135023I-2938J-4662D01*
G01X449646Y134995D01*
X449597Y134907D01*
Y134463D01*
X449646Y134375D01*
X449690Y134347D01*
G02X452262Y129685I-2938J-4661D01*
G02X446752Y124174I-5510J-1D01*
G02X442090Y126747I0J5510D01*
G01X442062Y126791D01*
X441974Y126840D01*
X441530D01*
X441442Y126791D01*
X441414Y126747D01*
G02X436752Y124174I-4662J2937D01*
G02X431242Y129685I1J5511D01*
G02X433814Y134347I5510J1D01*
G01X433858Y134375D01*
X433907Y134463D01*
Y134907D01*
X433858Y134995D01*
X433814Y135023D01*
G02Y144347I2938J4662D01*
G01X433858Y144375D01*
X433907Y144463D01*
Y144907D01*
X433858Y144995D01*
X433814Y145023D01*
G02Y154347I2938J4662D01*
G01X433858Y154375D01*
X433907Y154463D01*
Y154907D01*
X433858Y154995D01*
X433814Y155023D01*
G02X431242Y159685I2938J4661D01*
G02X436752Y165196I5510J1D01*
G02X441414Y162623I0J-5510D01*
G01X441442Y162579D01*
X441530Y162530D01*
G37*
G36*
G01X637793Y40521D02*
G02X634698Y44000I408J3479D01*
G02X634903Y45182I3502J1D01*
G03Y45318I-188J68D01*
G02X634698Y46500I3297J1181D01*
G02X638058Y50000I3503J0D01*
G03X638215Y50086I-7J200D01*
G02X641100Y51602I2885J-1987D01*
G02X644602Y48100I0J-3502D01*
G02X643351Y45417I-3503J0D01*
G01X643318Y45389D01*
X643281Y45313D01*
X643268Y44930D01*
X643299Y44852D01*
X643330Y44822D01*
G02X644402Y42300I-2431J-2522D01*
G02X640900Y38798I-3502J0D01*
G02X637939Y40429I0J3503D01*
G03X637793Y40521I-169J-107D01*
G37*
G36*
G01X1075308Y93848D02*
G02X1077200Y94402I1890J-2948D01*
G02Y87398I0J-3502D01*
G02X1075308Y87952I-2J3502D01*
G03X1075092I-108J-168D01*
G02X1073200Y87398I-1890J2948D01*
G02Y94402I0J3502D01*
G02X1075092Y93848I2J-3502D01*
G03X1075308I108J168D01*
G37*
G36*
G01X68400Y93092D02*
X67972Y93157D01*
X67879Y93125D01*
X67844Y93087D01*
G02Y106361I-7214J6637D01*
G01X67879Y106323D01*
X67972Y106291D01*
X68400Y106356D01*
X68479Y106415D01*
X68500Y106461D01*
G02X82795Y115526I14295J-6739D01*
G02Y83922I0J-15802D01*
G02X68500Y92987I0J15804D01*
G01X68479Y93033D01*
X68400Y93092D01*
G37*
G36*
G01X1128569Y123243D02*
X1128931D01*
X1129003Y123273D01*
X1129032Y123301D01*
G02X1131500Y124318I2468J-2486D01*
G02X1132919Y124018I1J-3502D01*
G03X1133081I81J183D01*
G02X1134500Y124318I1418J-3202D01*
G02Y117314I0J-3502D01*
G02X1133081Y117614I-1J3502D01*
G03X1132919I-81J-183D01*
G02X1131500Y117314I-1418J3202D01*
G02X1129032Y118331I0J3503D01*
G01X1129003Y118359D01*
X1128931Y118389D01*
X1128569D01*
X1128497Y118359D01*
X1128468Y118331D01*
G02X1126000Y117314I-2468J2486D01*
G02X1124581Y117614I-1J3502D01*
G03X1124419I-81J-183D01*
G02X1123000Y117314I-1418J3202D01*
G02Y124318I0J3502D01*
G02X1124419Y124018I1J-3502D01*
G03X1124581I81J183D01*
G02X1126000Y124318I1418J-3202D01*
G02X1128468Y123301I0J-3503D01*
G01X1128497Y123273D01*
X1128569Y123243D01*
G37*
G36*
G01X1114049Y129633D02*
G02X1115801Y130102I1751J-3033D01*
G02Y123098I0J-3502D01*
G02X1114049Y123567I-1J3502D01*
G02Y129633I1751J3033D01*
G37*
G36*
G01X1138250Y164134D02*
G02X1140000Y164602I1749J-3034D01*
G02Y157598I0J-3502D01*
G02X1138250Y158066I-1J3502D01*
G03X1138050I-100J-173D01*
G02X1136300Y157598I-1749J3034D01*
G02Y164602I0J3502D01*
G02X1138050Y164134I1J-3502D01*
G03X1138250I100J173D01*
G37*
G36*
G01X1018570Y169974D02*
X1018623Y170080D01*
G03X1018636Y170225I-179J89D01*
G02X1018498Y171200I3364J973D01*
G02X1025502I3502J0D01*
G02X1023239Y167924I-3503J0D01*
G03X1023130Y167826I70J-187D01*
G01X1023077Y167720D01*
G03X1023064Y167575I179J-89D01*
G02X1023202Y166600I-3364J-973D01*
G02X1023053Y165589I-3502J0D01*
G01X1023042Y165551D01*
X1023049Y165475D01*
X1023211Y165158D01*
X1023269Y165108D01*
X1023306Y165095D01*
G02X1025670Y161783I-1138J-3312D01*
G02X1024458Y159133I-3503J0D01*
G01X1024424Y159104D01*
X1024389Y159026D01*
Y158634D01*
X1024424Y158556D01*
X1024458Y158527D01*
G02X1025670Y155877I-2291J-2650D01*
G02X1022168Y152374I-3502J-1D01*
G02X1021810Y152393I6J3503D01*
G01X1021764Y152398D01*
X1021678Y152366D01*
X1021395Y152070D01*
X1021367Y151983D01*
X1021374Y151936D01*
G02X1021412Y151424I-3465J-515D01*
G02X1014406I-3503J0D01*
G02X1014645Y152693I3503J-3D01*
G03X1014641Y152848I-187J73D01*
G02X1014334Y154280I3196J1434D01*
G02X1015483Y156874I3503J0D01*
G03X1015548Y157037I-134J148D01*
G02X1015538Y157310I3492J265D01*
G02X1015837Y158728I3502J2D01*
G03Y158891I-183J82D01*
G02X1015528Y160330I3193J1438D01*
G02X1017278Y163363I3503J0D01*
G01X1017320Y163387D01*
X1017372Y163467D01*
X1017417Y163885D01*
X1017383Y163973D01*
X1017347Y164006D01*
G02X1016198Y166600I2354J2594D01*
G02X1018461Y169876I3503J0D01*
G03X1018570Y169974I-70J187D01*
G37*
G36*
G01X1138250Y175334D02*
G02X1140000Y175802I1749J-3034D01*
G02Y168798I0J-3502D01*
G02X1138250Y169266I-1J3502D01*
G03X1138050I-100J-173D01*
G02X1136300Y168798I-1749J3034D01*
G02Y175802I0J3502D01*
G02X1138050Y175334I1J-3502D01*
G03X1138250I100J173D01*
G37*
G36*
G01X1141998Y186729D02*
G02X1143490Y187062I1491J-3169D01*
G02Y180058I0J-3502D01*
G02X1141998Y180391I-1J3502D01*
G03X1141828I-85J-181D01*
G02X1140336Y180058I-1491J3169D01*
G02Y187062I0J3502D01*
G02X1141828Y186729I1J-3502D01*
G03X1141998I85J181D01*
G37*
G36*
G01X1019816Y188686D02*
G02X1020116Y187267I-3202J-1418D01*
G02X1013112I-3502J0D01*
G02X1013412Y188686I3502J1D01*
G03Y188848I-183J81D01*
G02X1013112Y190267I3202J1418D01*
G02X1020116I3502J0D01*
G02X1019816Y188848I-3502J-1D01*
G03Y188686I183J-81D01*
G37*
G36*
G01X1090702Y199419D02*
G02X1091002Y198000I-3202J-1418D01*
G02X1083998I-3502J0D01*
G02X1084298Y199419I3502J1D01*
G03Y199581I-183J81D01*
G02X1083998Y201000I3202J1418D01*
G02X1091002I3502J0D01*
G02X1090702Y199581I-3502J-1D01*
G03Y199419I183J-81D01*
G37*
G36*
G01X587867Y200690D02*
G02X586998Y203000I2633J2309D01*
G02X587203Y204182I3502J1D01*
G03Y204318I-188J68D01*
G02X586998Y205500I3297J1181D01*
G02X594002I3502J0D01*
G02X593797Y204318I-3502J-1D01*
G03Y204182I188J-68D01*
G02X594002Y203000I-3297J-1181D01*
G02X593133Y200690I-3502J-1D01*
G03X593083Y200559I150J-132D01*
G01Y200441D01*
G03X593133Y200310I200J1D01*
G02X594002Y198000I-2633J-2309D01*
G02X593797Y196818I-3502J-1D01*
G03Y196682I188J-68D01*
G02X594002Y195500I-3297J-1181D01*
G02X586998I-3502J0D01*
G02X587203Y196682I3502J1D01*
G03Y196818I-188J68D01*
G02X586998Y198000I3297J1181D01*
G02X587867Y200310I3502J1D01*
G03X587917Y200441I-150J132D01*
G01Y200559D01*
G03X587867Y200690I-200J-1D01*
G37*
G36*
G01X609367D02*
G02X608498Y203000I2633J2309D01*
G02X608703Y204182I3502J1D01*
G03Y204318I-188J68D01*
G02X608498Y205500I3297J1181D01*
G02X615502I3502J0D01*
G02X615297Y204318I-3502J-1D01*
G03Y204182I188J-68D01*
G02X615502Y203000I-3297J-1181D01*
G02X614633Y200690I-3502J-1D01*
G03X614583Y200559I150J-132D01*
G01Y200441D01*
G03X614633Y200310I200J1D01*
G02X615502Y198000I-2633J-2309D01*
G02X615297Y196818I-3502J-1D01*
G03Y196682I188J-68D01*
G02X615502Y195500I-3297J-1181D01*
G02X608498I-3502J0D01*
G02X608703Y196682I3502J1D01*
G03Y196818I-188J68D01*
G02X608498Y198000I3297J1181D01*
G02X609367Y200310I3502J1D01*
G03X609417Y200441I-150J132D01*
G01Y200559D01*
G03X609367Y200690I-200J-1D01*
G37*
G36*
G01X630867D02*
G02X629998Y203000I2633J2309D01*
G02X630203Y204182I3502J1D01*
G03Y204318I-188J68D01*
G02X629998Y205500I3297J1181D01*
G02X637002I3502J0D01*
G02X636797Y204318I-3502J-1D01*
G03Y204182I188J-68D01*
G02X637002Y203000I-3297J-1181D01*
G02X636133Y200690I-3502J-1D01*
G03X636083Y200559I150J-132D01*
G01Y200441D01*
G03X636133Y200310I200J1D01*
G02X637002Y198000I-2633J-2309D01*
G02X636797Y196818I-3502J-1D01*
G03Y196682I188J-68D01*
G02X637002Y195500I-3297J-1181D01*
G02X629998I-3502J0D01*
G02X630203Y196682I3502J1D01*
G03Y196818I-188J68D01*
G02X629998Y198000I3297J1181D01*
G02X630867Y200310I3502J1D01*
G03X630917Y200441I-150J132D01*
G01Y200559D01*
G03X630867Y200690I-200J-1D01*
G37*
G36*
G01X652367D02*
G02X651498Y203000I2633J2309D01*
G02X651703Y204182I3502J1D01*
G03Y204318I-188J68D01*
G02X651498Y205500I3297J1181D01*
G02X658502I3502J0D01*
G02X658297Y204318I-3502J-1D01*
G03Y204182I188J-68D01*
G02X658502Y203000I-3297J-1181D01*
G02X657633Y200690I-3502J-1D01*
G03X657583Y200559I150J-132D01*
G01Y200441D01*
G03X657633Y200310I200J1D01*
G02X658502Y198000I-2633J-2309D01*
G02X658297Y196818I-3502J-1D01*
G03Y196682I188J-68D01*
G02X658502Y195500I-3297J-1181D01*
G02X651498I-3502J0D01*
G02X651703Y196682I3502J1D01*
G03Y196818I-188J68D01*
G02X651498Y198000I3297J1181D01*
G02X652367Y200310I3502J1D01*
G03X652417Y200441I-150J132D01*
G01Y200559D01*
G03X652367Y200690I-200J-1D01*
G37*
G36*
G01X673867D02*
G02X672998Y203000I2633J2309D01*
G02X673203Y204182I3502J1D01*
G03Y204318I-188J68D01*
G02X672998Y205500I3297J1181D01*
G02X680002I3502J0D01*
G02X679797Y204318I-3502J-1D01*
G03Y204182I188J-68D01*
G02X680002Y203000I-3297J-1181D01*
G02X679133Y200690I-3502J-1D01*
G03X679083Y200559I150J-132D01*
G01Y200441D01*
G03X679133Y200310I200J1D01*
G02X680002Y198000I-2633J-2309D01*
G02X679797Y196818I-3502J-1D01*
G03Y196682I188J-68D01*
G02X680002Y195500I-3297J-1181D01*
G02X672998I-3502J0D01*
G02X673203Y196682I3502J1D01*
G03Y196818I-188J68D01*
G02X672998Y198000I3297J1181D01*
G02X673867Y200310I3502J1D01*
G03X673917Y200441I-150J132D01*
G01Y200559D01*
G03X673867Y200690I-200J-1D01*
G37*
G36*
G01X695357D02*
G02X694488Y203000I2633J2309D01*
G02X694693Y204182I3502J1D01*
G03Y204318I-188J68D01*
G02X694488Y205500I3297J1181D01*
G02X701492I3502J0D01*
G02X701287Y204318I-3502J-1D01*
G03Y204182I188J-68D01*
G02X701492Y203000I-3297J-1181D01*
G02X700623Y200690I-3502J-1D01*
G03X700573Y200559I150J-132D01*
G01Y200441D01*
G03X700623Y200310I200J1D01*
G02X701492Y198000I-2633J-2309D01*
G02X701287Y196818I-3502J-1D01*
G03Y196682I188J-68D01*
G02X701492Y195500I-3297J-1181D01*
G02X694488I-3502J0D01*
G02X694693Y196682I3502J1D01*
G03Y196818I-188J68D01*
G02X694488Y198000I3297J1181D01*
G02X695357Y200310I3502J1D01*
G03X695407Y200441I-150J132D01*
G01Y200559D01*
G03X695357Y200690I-200J-1D01*
G37*
G36*
G01X716857D02*
G02X715988Y203000I2633J2309D01*
G02X716193Y204182I3502J1D01*
G03Y204318I-188J68D01*
G02X715988Y205500I3297J1181D01*
G02X722992I3502J0D01*
G02X722787Y204318I-3502J-1D01*
G03Y204182I188J-68D01*
G02X722992Y203000I-3297J-1181D01*
G02X722123Y200690I-3502J-1D01*
G03X722073Y200559I150J-132D01*
G01Y200441D01*
G03X722123Y200310I200J1D01*
G02X722992Y198000I-2633J-2309D01*
G02X722787Y196818I-3502J-1D01*
G03Y196682I188J-68D01*
G02X722992Y195500I-3297J-1181D01*
G02X715988I-3502J0D01*
G02X716193Y196682I3502J1D01*
G03Y196818I-188J68D01*
G02X715988Y198000I3297J1181D01*
G02X716857Y200310I3502J1D01*
G03X716907Y200441I-150J132D01*
G01Y200559D01*
G03X716857Y200690I-200J-1D01*
G37*
G36*
G01X173348Y199403D02*
G02X171158Y202650I1312J3247D01*
G02X171501Y204164I3503J2D01*
G03Y204336I-180J86D01*
G02X171158Y205850I3160J1512D01*
G02X178162I3502J0D01*
G02X177819Y204336I-3503J-2D01*
G03Y204164I180J-86D01*
G02X178162Y202650I-3160J-1512D01*
G02X177677Y200871I-3502J-1D01*
G01X177655Y200834D01*
X177646Y200747D01*
X177772Y200377D01*
X177832Y200314D01*
X177872Y200297D01*
G02X177932Y200273I-1271J-3264D01*
G03X178088I78J184D01*
G02X179460Y200552I1370J-3223D01*
G02X180784Y200292I0J-3501D01*
G03X180936I76J186D01*
G02X182260Y200552I1324J-3241D01*
G02Y193548I0J-3502D01*
G02X180936Y193808I0J3501D01*
G03X180784I-76J-186D01*
G02X179460Y193548I-1324J3241D01*
G02X178088Y193827I-2J3502D01*
G03X177932I-78J-184D01*
G02X176560Y193548I-1370J3223D01*
G02X173058Y197050I0J3502D01*
G02X173543Y198829I3502J1D01*
G01X173565Y198866D01*
X173574Y198953D01*
X173448Y199323D01*
X173388Y199386D01*
X173348Y199403D01*
G37*
G36*
G01X280367Y201190D02*
G02X279498Y203500I2633J2309D01*
G02X279703Y204682I3502J1D01*
G03Y204818I-188J68D01*
G02X279498Y206000I3297J1181D01*
G02X286502I3502J0D01*
G02X286297Y204818I-3502J-1D01*
G03Y204682I188J-68D01*
G02X286502Y203500I-3297J-1181D01*
G02X285633Y201190I-3502J-1D01*
G03X285583Y201059I150J-132D01*
G01Y200941D01*
G03X285633Y200810I200J1D01*
G02X286502Y198500I-2633J-2309D01*
G02X286297Y197318I-3502J-1D01*
G03Y197182I188J-68D01*
G02X286502Y196000I-3297J-1181D01*
G02X279498I-3502J0D01*
G02X279703Y197182I3502J1D01*
G03Y197318I-188J68D01*
G02X279498Y198500I3297J1181D01*
G02X280367Y200810I3502J1D01*
G03X280417Y200941I-150J132D01*
G01Y201059D01*
G03X280367Y201190I-200J-1D01*
G37*
G36*
G01X301867D02*
G02X300998Y203500I2633J2309D01*
G02X301203Y204682I3502J1D01*
G03Y204818I-188J68D01*
G02X300998Y206000I3297J1181D01*
G02X308002I3502J0D01*
G02X307797Y204818I-3502J-1D01*
G03Y204682I188J-68D01*
G02X308002Y203500I-3297J-1181D01*
G02X307133Y201190I-3502J-1D01*
G03X307083Y201059I150J-132D01*
G01Y200941D01*
G03X307133Y200810I200J1D01*
G02X308002Y198500I-2633J-2309D01*
G02X307797Y197318I-3502J-1D01*
G03Y197182I188J-68D01*
G02X308002Y196000I-3297J-1181D01*
G02X300998I-3502J0D01*
G02X301203Y197182I3502J1D01*
G03Y197318I-188J68D01*
G02X300998Y198500I3297J1181D01*
G02X301867Y200810I3502J1D01*
G03X301917Y200941I-150J132D01*
G01Y201059D01*
G03X301867Y201190I-200J-1D01*
G37*
G36*
G01X323367D02*
G02X322498Y203500I2633J2309D01*
G02X322703Y204682I3502J1D01*
G03Y204818I-188J68D01*
G02X322498Y206000I3297J1181D01*
G02X329502I3502J0D01*
G02X329297Y204818I-3502J-1D01*
G03Y204682I188J-68D01*
G02X329502Y203500I-3297J-1181D01*
G02X328633Y201190I-3502J-1D01*
G03X328583Y201059I150J-132D01*
G01Y200941D01*
G03X328633Y200810I200J1D01*
G02X329502Y198500I-2633J-2309D01*
G02X329297Y197318I-3502J-1D01*
G03Y197182I188J-68D01*
G02X329502Y196000I-3297J-1181D01*
G02X322498I-3502J0D01*
G02X322703Y197182I3502J1D01*
G03Y197318I-188J68D01*
G02X322498Y198500I3297J1181D01*
G02X323367Y200810I3502J1D01*
G03X323417Y200941I-150J132D01*
G01Y201059D01*
G03X323367Y201190I-200J-1D01*
G37*
G36*
G01X344867D02*
G02X343998Y203500I2633J2309D01*
G02X344203Y204682I3502J1D01*
G03Y204818I-188J68D01*
G02X343998Y206000I3297J1181D01*
G02X351002I3502J0D01*
G02X350797Y204818I-3502J-1D01*
G03Y204682I188J-68D01*
G02X351002Y203500I-3297J-1181D01*
G02X350133Y201190I-3502J-1D01*
G03X350083Y201059I150J-132D01*
G01Y200941D01*
G03X350133Y200810I200J1D01*
G02X351002Y198500I-2633J-2309D01*
G02X350797Y197318I-3502J-1D01*
G03Y197182I188J-68D01*
G02X351002Y196000I-3297J-1181D01*
G02X343998I-3502J0D01*
G02X344203Y197182I3502J1D01*
G03Y197318I-188J68D01*
G02X343998Y198500I3297J1181D01*
G02X344867Y200810I3502J1D01*
G03X344917Y200941I-150J132D01*
G01Y201059D01*
G03X344867Y201190I-200J-1D01*
G37*
G36*
G01X366367D02*
G02X365498Y203500I2633J2309D01*
G02X365703Y204682I3502J1D01*
G03Y204818I-188J68D01*
G02X365498Y206000I3297J1181D01*
G02X372502I3502J0D01*
G02X372297Y204818I-3502J-1D01*
G03Y204682I188J-68D01*
G02X372502Y203500I-3297J-1181D01*
G02X371633Y201190I-3502J-1D01*
G03X371583Y201059I150J-132D01*
G01Y200941D01*
G03X371633Y200810I200J1D01*
G02X372502Y198500I-2633J-2309D01*
G02X372297Y197318I-3502J-1D01*
G03Y197182I188J-68D01*
G02X372502Y196000I-3297J-1181D01*
G02X365498I-3502J0D01*
G02X365703Y197182I3502J1D01*
G03Y197318I-188J68D01*
G02X365498Y198500I3297J1181D01*
G02X366367Y200810I3502J1D01*
G03X366417Y200941I-150J132D01*
G01Y201059D01*
G03X366367Y201190I-200J-1D01*
G37*
G36*
G01X387867D02*
G02X386998Y203500I2633J2309D01*
G02X387203Y204682I3502J1D01*
G03Y204818I-188J68D01*
G02X386998Y206000I3297J1181D01*
G02X394002I3502J0D01*
G02X393797Y204818I-3502J-1D01*
G03Y204682I188J-68D01*
G02X394002Y203500I-3297J-1181D01*
G02X393133Y201190I-3502J-1D01*
G03X393083Y201059I150J-132D01*
G01Y200941D01*
G03X393133Y200810I200J1D01*
G02X394002Y198500I-2633J-2309D01*
G02X393797Y197318I-3502J-1D01*
G03Y197182I188J-68D01*
G02X394002Y196000I-3297J-1181D01*
G02X386998I-3502J0D01*
G02X387203Y197182I3502J1D01*
G03Y197318I-188J68D01*
G02X386998Y198500I3297J1181D01*
G02X387867Y200810I3502J1D01*
G03X387917Y200941I-150J132D01*
G01Y201059D01*
G03X387867Y201190I-200J-1D01*
G37*
G36*
G01X409367D02*
G02X408498Y203500I2633J2309D01*
G02X408703Y204682I3502J1D01*
G03Y204818I-188J68D01*
G02X408498Y206000I3297J1181D01*
G02X415502I3502J0D01*
G02X415297Y204818I-3502J-1D01*
G03Y204682I188J-68D01*
G02X415502Y203500I-3297J-1181D01*
G02X414633Y201190I-3502J-1D01*
G03X414583Y201059I150J-132D01*
G01Y200941D01*
G03X414633Y200810I200J1D01*
G02X415502Y198500I-2633J-2309D01*
G02X415297Y197318I-3502J-1D01*
G03Y197182I188J-68D01*
G02X415502Y196000I-3297J-1181D01*
G02X408498I-3502J0D01*
G02X408703Y197182I3502J1D01*
G03Y197318I-188J68D01*
G02X408498Y198500I3297J1181D01*
G02X409367Y200810I3502J1D01*
G03X409417Y200941I-150J132D01*
G01Y201059D01*
G03X409367Y201190I-200J-1D01*
G37*
G36*
G01X190958Y206781D02*
G02X190658Y208200I3202J1418D01*
G02X194160Y211702I3502J0D01*
G02X195579Y211402I1J-3502D01*
G03X195741I81J183D01*
G02X197160Y211702I1418J-3202D01*
G02X198579Y211402I1J-3502D01*
G03X198741I81J183D01*
G02X200160Y211702I1418J-3202D01*
G02X203662Y208200I0J-3502D01*
G02X203362Y206781I-3502J-1D01*
G03Y206619I183J-81D01*
G02X203662Y205200I-3202J-1418D01*
G02X200160Y201698I-3502J0D01*
G02X198741Y201998I-1J3502D01*
G03X198579I-81J-183D01*
G02X197160Y201698I-1418J3202D01*
G02X195741Y201998I-1J3502D01*
G03X195579I-81J-183D01*
G02X194160Y201698I-1418J3202D01*
G02X190658Y205200I0J3502D01*
G02X190958Y206619I3502J1D01*
G03Y206781I-183J81D01*
G37*
G36*
G01X188462Y206769D02*
G02X188762Y205350I-3202J-1418D01*
G02X181758I-3502J0D01*
G02X182058Y206769I3502J1D01*
G03Y206931I-183J81D01*
G02X181758Y208350I3202J1418D01*
G02X188762I3502J0D01*
G02X188462Y206931I-3502J-1D01*
G03Y206769I183J-81D01*
G37*
G36*
G01X149247Y224908D02*
G02X148832Y226563I3087J1654D01*
G02X149247Y228218I3502J1D01*
G03Y228408I-176J95D01*
G02X148832Y230063I3087J1654D01*
G02X152065Y233555I3502J0D01*
G03X152211Y233636I-15J200D01*
G02X155034Y235066I2824J-2073D01*
G02X158536Y231563I-1J-3503D01*
G02X158121Y229908I-3502J-1D01*
G03Y229718I176J-95D01*
G02X158536Y228063I-3087J-1654D01*
G02X158121Y226408I-3502J-1D01*
G03Y226218I176J-95D01*
G02X158536Y224563I-3087J-1654D01*
G02X155303Y221071I-3502J0D01*
G03X155157Y220990I15J-200D01*
G02X154140Y220062I-2823J2073D01*
G03X154048Y219846I103J-171D01*
G02X154136Y219063I-3414J-780D01*
G02X147132I-3502J0D01*
G02X148828Y222064I3503J0D01*
G03X148920Y222280I-103J171D01*
G02X148832Y223063I3414J780D01*
G02X149247Y224718I3502J1D01*
G03Y224908I-176J95D01*
G37*
G36*
G01X1064581Y261202D02*
G02X1066000Y261502I1418J-3202D01*
G02X1067419Y261202I1J-3502D01*
G03X1067581I81J183D01*
G02X1069000Y261502I1418J-3202D01*
G02X1070419Y261202I1J-3502D01*
G03X1070581I81J183D01*
G02X1072000Y261502I1418J-3202D01*
G02X1075502Y258000I0J-3502D01*
G02X1075202Y256581I-3502J-1D01*
G03Y256419I183J-81D01*
G02X1075502Y255000I-3202J-1418D01*
G02X1072000Y251498I-3502J0D01*
G02X1070581Y251798I-1J3502D01*
G03X1070419I-81J-183D01*
G02X1069611Y251551I-1420J3202D01*
G03X1069449Y251389I35J-197D01*
G02X1069202Y250581I-3449J612D01*
G03Y250419I183J-81D01*
G02X1069449Y249611I-3202J-1420D01*
G03X1069611Y249449I197J35D01*
G02X1070419Y249202I-612J-3449D01*
G03X1070581I81J183D01*
G02X1072000Y249502I1418J-3202D01*
G02X1075502Y246000I0J-3502D01*
G02X1075202Y244581I-3502J-1D01*
G03Y244419I183J-81D01*
G02X1075502Y243000I-3202J-1418D01*
G02X1072000Y239498I-3502J0D01*
G02X1070581Y239798I-1J3502D01*
G03X1070419I-81J-183D01*
G02X1069000Y239498I-1418J3202D01*
G02X1067581Y239798I-1J3502D01*
G03X1067419I-81J-183D01*
G02X1066000Y239498I-1418J3202D01*
G02X1064581Y239798I-1J3502D01*
G03X1064419I-81J-183D01*
G02X1063000Y239498I-1418J3202D01*
G02X1061581Y239798I-1J3502D01*
G03X1061419I-81J-183D01*
G02X1060000Y239498I-1418J3202D01*
G02X1056498Y243000I0J3502D01*
G02X1056798Y244419I3502J1D01*
G03Y244581I-183J81D01*
G02X1056498Y246000I3202J1418D01*
G02X1056798Y247419I3502J1D01*
G03Y247581I-183J81D01*
G02X1056498Y249000I3202J1418D01*
G02X1056798Y250419I3502J1D01*
G03Y250581I-183J81D01*
G02X1056498Y252000I3202J1418D01*
G02X1056798Y253419I3502J1D01*
G03Y253581I-183J81D01*
G02X1056498Y255000I3202J1418D01*
G02X1056798Y256419I3502J1D01*
G03Y256581I-183J81D01*
G02X1056498Y258000I3202J1418D01*
G02X1060000Y261502I3502J0D01*
G02X1061419Y261202I1J-3502D01*
G03X1061581I81J183D01*
G02X1063000Y261502I1418J-3202D01*
G02X1064419Y261202I1J-3502D01*
G03X1064581I81J183D01*
G37*
G36*
G01X105398Y257141D02*
G02X105098Y258560I3202J1418D01*
G02X105398Y259979I3502J1D01*
G03Y260141I-183J81D01*
G02X105098Y261560I3202J1418D01*
G02X108600Y265062I3502J0D01*
G02X110019Y264762I1J-3502D01*
G03X110181I81J183D01*
G02X111600Y265062I1418J-3202D01*
G02X115102Y261560I0J-3502D01*
G02X114802Y260141I-3502J-1D01*
G03Y259979I183J-81D01*
G02X115102Y258560I-3202J-1418D01*
G02X114802Y257141I-3502J-1D01*
G03Y256979I183J-81D01*
G02X115102Y255560I-3202J-1418D01*
G02X111600Y252058I-3502J0D01*
G02X110181Y252358I-1J3502D01*
G03X110019I-81J-183D01*
G02X108600Y252058I-1418J3202D01*
G02X105098Y255560I0J3502D01*
G02X105398Y256979I3502J1D01*
G03Y257141I-183J81D01*
G37*
G36*
G01X43435Y269857D02*
G02X38780Y267196I-4655J2741D01*
G02X33378Y272598I0J5402D01*
G02X34447Y275825I5402J1D01*
G03Y276064I-160J120D01*
G02X33378Y279291I4333J3226D01*
G02X38780Y284694I5402J1D01*
G02X43435Y282032I-1J-5403D01*
G01X43462Y281986D01*
X43554Y281934D01*
X44006D01*
X44098Y281986D01*
X44125Y282032D01*
G02X48780Y284694I4656J-2741D01*
G02X54182Y279291I-1J-5403D01*
G02X53113Y276064I-5402J-1D01*
G03Y275825I160J-119D01*
G02X54182Y272598I-4333J-3226D01*
G02X48780Y267196I-5402J0D01*
G02X44125Y269857I0J5402D01*
G01X44098Y269903D01*
X44006Y269955D01*
X43554D01*
X43462Y269903D01*
X43435Y269857D01*
G37*
G36*
G01X561243Y272218D02*
X561401Y272604D01*
X561394Y272697D01*
X561369Y272738D01*
G02X560128Y277204I7411J4465D01*
G02X568780Y285856I8652J0D01*
G02X575949Y282049I1J-8652D01*
G01X575977Y282008D01*
X576064Y281961D01*
X576496D01*
X576583Y282008D01*
X576611Y282049D01*
G02X583780Y285856I7168J-4845D01*
G02Y268552I0J-8652D01*
G02X576611Y272359I-1J8652D01*
G01X576583Y272400D01*
X576496Y272447D01*
X576064D01*
X575977Y272400D01*
X575949Y272359D01*
G02X568780Y268552I-7168J4845D01*
G02X567856Y268601I-4J8652D01*
G01X567808Y268606D01*
X567721Y268574D01*
X567437Y268268D01*
X567411Y268178D01*
X567420Y268131D01*
G02X567504Y267204I-5018J-922D01*
G02X557300I-5102J0D01*
G02X561126Y272144I5102J0D01*
G01X561173Y272157D01*
X561243Y272218D01*
G37*
G36*
G01X718724D02*
X718882Y272604D01*
X718875Y272697D01*
X718850Y272738D01*
G02X717608Y277204I7411J4467D01*
G02X726261Y285856I8653J-1D01*
G02X733430Y282049I1J-8652D01*
G01X733458Y282008D01*
X733545Y281961D01*
X733977D01*
X734064Y282008D01*
X734092Y282049D01*
G02X741261Y285856I7168J-4845D01*
G02Y268552I0J-8652D01*
G02X734092Y272359I-1J8652D01*
G01X734064Y272400D01*
X733977Y272447D01*
X733545D01*
X733458Y272400D01*
X733430Y272359D01*
G02X726261Y268552I-7168J4845D01*
G02X725337Y268601I-4J8652D01*
G01X725289Y268606D01*
X725202Y268574D01*
X724918Y268268D01*
X724892Y268178D01*
X724901Y268131D01*
G02X724986Y267204I-5018J-928D01*
G02X714780I-5103J0D01*
G02X718607Y272144I5102J0D01*
G01X718654Y272157D01*
X718724Y272218D01*
G37*
G36*
G01X274082Y284635D02*
G02X277219Y286580I3137J-1557D01*
G02X279111Y286026I2J-3502D01*
G03X279327I108J168D01*
G02X281219Y286580I1890J-2948D01*
G02X283111Y286026I2J-3502D01*
G03X283327I108J168D01*
G02X285219Y286580I1890J-2948D01*
G02X288722Y283078I1J-3502D01*
G02X288167Y281186I-3502J0D01*
G03Y280970I168J-108D01*
G02Y277186I-2947J-1892D01*
G03Y276970I168J-108D01*
G02Y273186I-2947J-1892D01*
G03Y272970I168J-108D01*
G02X288722Y271078I-2947J-1892D01*
G02X285219Y267576I-3503J1D01*
G02X283327Y268130I-2J3502D01*
G03X283111I-108J-168D01*
G02X281219Y267576I-1890J2948D01*
G02X279327Y268130I-2J3502D01*
G03X279111I-108J-168D01*
G02X277219Y267576I-1890J2948D01*
G02X274001Y269696I0J3502D01*
G01X273983Y269736D01*
X273919Y269795D01*
X273544Y269911D01*
X273458Y269900D01*
X273421Y269877D01*
G02X268819Y268552I-4601J7327D01*
G02X261650Y272359I-1J8652D01*
G01X261622Y272400D01*
X261535Y272447D01*
X261103D01*
X261016Y272400D01*
X260988Y272359D01*
G02X253819Y268552I-7168J4845D01*
G02X252895Y268601I-4J8652D01*
G01X252847Y268606D01*
X252760Y268574D01*
X252476Y268268D01*
X252450Y268178D01*
X252459Y268131D01*
G02X252544Y267204I-5018J-928D01*
G02X242338I-5103J0D01*
G02X246165Y272144I5102J0D01*
G01X246212Y272157D01*
X246282Y272218D01*
X246440Y272604D01*
X246433Y272697D01*
X246408Y272738D01*
G02X245166Y277204I7411J4467D01*
G02X253819Y285856I8653J-1D01*
G02X260988Y282049I1J-8652D01*
G01X261016Y282008D01*
X261103Y281961D01*
X261535D01*
X261622Y282008D01*
X261650Y282049D01*
G02X268819Y285856I7168J-4845D01*
G02X273507Y284477I2J-8652D01*
G01X273543Y284453D01*
X273626Y284440D01*
X273998Y284543D01*
X274062Y284596D01*
X274082Y284635D01*
G37*
G36*
G01X431368Y284755D02*
G02X434499Y286688I3131J-1569D01*
G02X436391Y286134I2J-3502D01*
G03X436607I108J168D01*
G02X438499Y286688I1890J-2948D01*
G02X440391Y286134I2J-3502D01*
G03X440607I108J168D01*
G02X442499Y286688I1890J-2948D01*
G02X446002Y283186I1J-3502D01*
G02X445447Y281294I-3502J0D01*
G03Y281078I168J-108D01*
G02Y277294I-2947J-1892D01*
G03Y277078I168J-108D01*
G02Y273294I-2947J-1892D01*
G03Y273078I168J-108D01*
G02X446002Y271186I-2947J-1892D01*
G02X442499Y267684I-3503J1D01*
G02X440607Y268238I-2J3502D01*
G03X440391I-108J-168D01*
G02X438499Y267684I-1890J2948D01*
G02X436607Y268238I-2J3502D01*
G03X436391I-108J-168D01*
G02X434499Y267684I-1890J2948D01*
G02X431355Y269642I0J3503D01*
G01X431337Y269680D01*
X431272Y269734D01*
X430908Y269840D01*
X430825Y269829D01*
X430789Y269807D01*
G02X426299Y268552I-4488J7398D01*
G02X419130Y272359I-1J8652D01*
G01X419102Y272400D01*
X419015Y272447D01*
X418583D01*
X418496Y272400D01*
X418468Y272359D01*
G02X411299Y268552I-7168J4845D01*
G02X410375Y268601I-4J8652D01*
G01X410327Y268606D01*
X410240Y268574D01*
X409956Y268268D01*
X409930Y268178D01*
X409939Y268131D01*
G02X410024Y267204I-5018J-928D01*
G02X399818I-5103J0D01*
G02X403645Y272144I5102J0D01*
G01X403692Y272157D01*
X403762Y272218D01*
X403920Y272604D01*
X403913Y272697D01*
X403888Y272738D01*
G02X402646Y277204I7411J4467D01*
G02X411299Y285856I8653J-1D01*
G02X418468Y282049I1J-8652D01*
G01X418496Y282008D01*
X418583Y281961D01*
X419015D01*
X419102Y282008D01*
X419130Y282049D01*
G02X426299Y285856I7168J-4845D01*
G02X430802Y284593I2J-8652D01*
G01X430838Y284570D01*
X430920Y284559D01*
X431285Y284664D01*
X431348Y284717D01*
X431368Y284755D01*
G37*
G36*
G01X43571Y290101D02*
G02X38780Y287196I-4791J2498D01*
G02X33378Y292598I0J5402D01*
G02X34447Y295825I5402J1D01*
G03Y296064I-160J120D01*
G02X33378Y299291I4333J3226D01*
G02X38780Y304694I5402J1D01*
G02X43435Y302032I-1J-5403D01*
G01X43462Y301986D01*
X43554Y301934D01*
X44006D01*
X44098Y301986D01*
X44125Y302032D01*
G02X48780Y304694I4656J-2741D01*
G02X54182Y299291I-1J-5403D01*
G02X53113Y296064I-5402J-1D01*
G03Y295825I160J-119D01*
G02X54182Y292598I-4333J-3226D01*
G02X48780Y287196I-5402J0D01*
G02X43988Y290102I-1J5403D01*
G03X43806Y290210I-177J-92D01*
G02X43745Y290209I-119J5398D01*
G03X43571Y290101I4J-200D01*
G37*
G36*
G01X1064581Y308702D02*
G02X1066000Y309002I1418J-3202D01*
G02X1067419Y308702I1J-3502D01*
G03X1067581I81J183D01*
G02X1069000Y309002I1418J-3202D01*
G02X1070419Y308702I1J-3502D01*
G03X1070581I81J183D01*
G02X1072000Y309002I1418J-3202D01*
G02X1075502Y305500I0J-3502D01*
G02X1075202Y304081I-3502J-1D01*
G03Y303919I183J-81D01*
G02X1075502Y302500I-3202J-1418D01*
G02X1072000Y298998I-3502J0D01*
G02X1070581Y299298I-1J3502D01*
G03X1070419I-81J-183D01*
G02X1069611Y299051I-1420J3202D01*
G03X1069449Y298889I35J-197D01*
G02X1069202Y298081I-3449J612D01*
G03Y297919I183J-81D01*
G02X1069449Y297111I-3202J-1420D01*
G03X1069611Y296949I197J35D01*
G02X1070419Y296702I-612J-3449D01*
G03X1070581I81J183D01*
G02X1072000Y297002I1418J-3202D01*
G02X1075502Y293500I0J-3502D01*
G02X1075202Y292081I-3502J-1D01*
G03Y291919I183J-81D01*
G02X1075502Y290500I-3202J-1418D01*
G02X1072000Y286998I-3502J0D01*
G02X1070581Y287298I-1J3502D01*
G03X1070419I-81J-183D01*
G02X1069000Y286998I-1418J3202D01*
G02X1067581Y287298I-1J3502D01*
G03X1067419I-81J-183D01*
G02X1066000Y286998I-1418J3202D01*
G02X1064581Y287298I-1J3502D01*
G03X1064419I-81J-183D01*
G02X1063000Y286998I-1418J3202D01*
G02X1061581Y287298I-1J3502D01*
G03X1061419I-81J-183D01*
G02X1060000Y286998I-1418J3202D01*
G02X1056498Y290500I0J3502D01*
G02X1056798Y291919I3502J1D01*
G03Y292081I-183J81D01*
G02X1056498Y293500I3202J1418D01*
G02X1056798Y294919I3502J1D01*
G03Y295081I-183J81D01*
G02X1056498Y296500I3202J1418D01*
G02X1056798Y297919I3502J1D01*
G03Y298081I-183J81D01*
G02X1056498Y299500I3202J1418D01*
G02X1056798Y300919I3502J1D01*
G03Y301081I-183J81D01*
G02X1056498Y302500I3202J1418D01*
G02X1056798Y303919I3502J1D01*
G03Y304081I-183J81D01*
G02X1056498Y305500I3202J1418D01*
G02X1060000Y309002I3502J0D01*
G02X1061419Y308702I1J-3502D01*
G03X1061581I81J183D01*
G02X1063000Y309002I1418J-3202D01*
G02X1064419Y308702I1J-3502D01*
G03X1064581I81J183D01*
G37*
G36*
G01X43781Y349915D02*
G02X48780Y354726I4999J-192D01*
G02X53782Y349724I0J-5002D01*
G02X48971Y344725I-5003J0D01*
G03X48779Y344533I8J-200D01*
G02X43780Y339722I-4999J192D01*
G02X38778Y344724I0J5002D01*
G02X43589Y349723I5003J0D01*
G03X43781Y349915I-8J200D01*
G37*
G36*
G01X1059200Y356470D02*
X1059308Y356917D01*
X1059276Y357021D01*
X1059236Y357058D01*
G02X1058098Y359642I2365J2584D01*
G02X1065102I3502J0D01*
G02X1063920Y357018I-3502J-1D01*
G01X1063879Y356982D01*
X1063845Y356880D01*
X1063940Y356433D01*
X1064011Y356354D01*
X1064063Y356337D01*
G02X1064419Y356202I-1062J-3337D01*
G03X1064581I81J183D01*
G02X1066000Y356502I1418J-3202D01*
G02X1067419Y356202I1J-3502D01*
G03X1067581I81J183D01*
G02X1069000Y356502I1418J-3202D01*
G02X1070419Y356202I1J-3502D01*
G03X1070581I81J183D01*
G02X1072000Y356502I1418J-3202D01*
G02X1075502Y353000I0J-3502D01*
G02X1075202Y351581I-3502J-1D01*
G03Y351419I183J-81D01*
G02X1075502Y350000I-3202J-1418D01*
G02X1072000Y346498I-3502J0D01*
G02X1070581Y346798I-1J3502D01*
G03X1070419I-81J-183D01*
G02X1069611Y346551I-1420J3202D01*
G03X1069449Y346389I35J-197D01*
G02X1069202Y345581I-3449J612D01*
G03Y345419I183J-81D01*
G02X1069449Y344611I-3202J-1420D01*
G03X1069611Y344449I197J35D01*
G02X1070419Y344202I-612J-3449D01*
G03X1070581I81J183D01*
G02X1072000Y344502I1418J-3202D01*
G02X1075502Y341000I0J-3502D01*
G02X1075202Y339581I-3502J-1D01*
G03Y339419I183J-81D01*
G02X1075502Y338000I-3202J-1418D01*
G02X1072000Y334498I-3502J0D01*
G02X1070581Y334798I-1J3502D01*
G03X1070419I-81J-183D01*
G02X1069000Y334498I-1418J3202D01*
G02X1067581Y334798I-1J3502D01*
G03X1067419I-81J-183D01*
G02X1066000Y334498I-1418J3202D01*
G02X1064581Y334798I-1J3502D01*
G03X1064419I-81J-183D01*
G02X1063000Y334498I-1418J3202D01*
G02X1061581Y334798I-1J3502D01*
G03X1061419I-81J-183D01*
G02X1060000Y334498I-1418J3202D01*
G02X1056498Y338000I0J3502D01*
G02X1056798Y339419I3502J1D01*
G03Y339581I-183J81D01*
G02X1056498Y341000I3202J1418D01*
G02X1056798Y342419I3502J1D01*
G03Y342581I-183J81D01*
G02X1056498Y344000I3202J1418D01*
G02X1056798Y345419I3502J1D01*
G03Y345581I-183J81D01*
G02X1056498Y347000I3202J1418D01*
G02X1056798Y348419I3502J1D01*
G03Y348581I-183J81D01*
G02X1056498Y350000I3202J1418D01*
G02X1056798Y351419I3502J1D01*
G03Y351581I-183J81D01*
G02X1056498Y353000I3202J1418D01*
G02X1059072Y356377I3502J0D01*
G01X1059125Y356392D01*
X1059200Y356470D01*
G37*
G36*
G01X946985Y388121D02*
X947372D01*
X947450Y388156D01*
X947479Y388189D01*
G02X950110Y389380I2632J-2312D01*
G02X951529Y389079I-2J-3503D01*
G03X951691I81J183D01*
G02X953110Y389380I1421J-3202D01*
G02Y382374I0J-3503D01*
G02X951691Y382675I2J3503D01*
G03X951529I-81J-183D01*
G02X950110Y382374I-1421J3202D01*
G02X947479Y383565I1J3503D01*
G01X947450Y383598D01*
X947372Y383633D01*
X946985D01*
X946907Y383598D01*
X946878Y383565D01*
G02X944247Y382374I-2632J2312D01*
G02X942828Y382675I2J3503D01*
G03X942666I-81J-183D01*
G02X941247Y382374I-1421J3202D01*
G02X938162Y384219I0J3502D01*
G01X938135Y384269D01*
X938039Y384325D01*
X937571Y384318D01*
X937477Y384259D01*
X937452Y384208D01*
G02X934317Y382268I-3135J1563D01*
G02X932898Y382569I2J3503D01*
G03X932736I-81J-183D01*
G02X931317Y382268I-1421J3202D01*
G02X928686Y383459I1J3503D01*
G01X928657Y383492D01*
X928579Y383527D01*
X928192D01*
X928114Y383492D01*
X928085Y383459D01*
G02X925454Y382268I-2632J2312D01*
G02X924035Y382569I2J3503D01*
G03X923873I-81J-183D01*
G02X922454Y382268I-1421J3202D01*
G02X919320Y384207I0J3502D01*
G01X919295Y384258D01*
X919201Y384317D01*
X918732Y384324D01*
X918637Y384268D01*
X918610Y384218D01*
G02X915525Y382374I-3085J1659D01*
G02X914106Y382675I2J3503D01*
G03X913944I-81J-183D01*
G02X912525Y382374I-1421J3202D01*
G02X909894Y383565I1J3503D01*
G01X909865Y383598D01*
X909787Y383633D01*
X909400D01*
X909322Y383598D01*
X909293Y383565D01*
G02X906662Y382374I-2632J2312D01*
G02X905243Y382675I2J3503D01*
G03X905081I-81J-183D01*
G02X903662Y382374I-1421J3202D01*
G02Y389380I0J3503D01*
G02X905081Y389079I-2J-3503D01*
G03X905243I81J183D01*
G02X906662Y389380I1421J-3202D01*
G02X909293Y388189I-1J-3503D01*
G01X909322Y388156D01*
X909400Y388121D01*
X909787D01*
X909865Y388156D01*
X909894Y388189D01*
G02X912525Y389380I2632J-2312D01*
G02X913944Y389079I-2J-3503D01*
G03X914106I81J183D01*
G02X915525Y389380I1421J-3202D01*
G02X918659Y387441I0J-3502D01*
G01X918684Y387390D01*
X918778Y387331D01*
X919247Y387324D01*
X919342Y387380D01*
X919369Y387430D01*
G02X922454Y389274I3085J-1659D01*
G02X923873Y388973I-2J-3503D01*
G03X924035I81J183D01*
G02X925454Y389274I1421J-3202D01*
G02X928085Y388083I-1J-3503D01*
G01X928114Y388050D01*
X928192Y388015D01*
X928579D01*
X928657Y388050D01*
X928686Y388083D01*
G02X931317Y389274I2632J-2312D01*
G02X932736Y388973I-2J-3503D01*
G03X932898I81J183D01*
G02X934317Y389274I1421J-3202D01*
G02X937402Y387429I0J-3502D01*
G01X937429Y387379D01*
X937525Y387323D01*
X937993Y387330D01*
X938087Y387389D01*
X938112Y387440D01*
G02X941247Y389380I3135J-1563D01*
G02X942666Y389079I-2J-3503D01*
G03X942828I81J183D01*
G02X944247Y389380I1421J-3202D01*
G02X946878Y388189I-1J-3503D01*
G01X946907Y388156D01*
X946985Y388121D01*
G37*
G36*
G01X853128Y388122D02*
X853515D01*
X853593Y388157D01*
X853622Y388190D01*
G02X856253Y389380I2630J-2312D01*
G02X857672Y389080I1J-3502D01*
G03X857834I81J183D01*
G02X859253Y389380I1418J-3202D01*
G02X862110Y387903I0J-3502D01*
G01X862138Y387864D01*
X862222Y387820D01*
X862641Y387813D01*
X862726Y387854D01*
X862755Y387892D01*
G02X865542Y389274I2788J-2121D01*
G02X866961Y388973I-2J-3503D01*
G03X867123I81J183D01*
G02X868542Y389274I1421J-3202D01*
G02X871173Y388083I-1J-3503D01*
G01X871202Y388050D01*
X871280Y388015D01*
X871667D01*
X871745Y388050D01*
X871774Y388083D01*
G02X874405Y389274I2632J-2312D01*
G02X875824Y388973I-2J-3503D01*
G03X875986I81J183D01*
G02X877405Y389274I1421J-3202D01*
G02X880467Y387472I0J-3503D01*
G03X880642Y387369I175J97D01*
G01X880991D01*
G03X881166Y387472I0J200D01*
G02X884228Y389274I3062J-1701D01*
G02X885647Y388973I-2J-3503D01*
G03X885809I81J183D01*
G02X887228Y389274I1421J-3202D01*
G02X889859Y388083I-1J-3503D01*
G01X889888Y388050D01*
X889966Y388015D01*
X890353D01*
X890431Y388050D01*
X890460Y388083D01*
G02X893091Y389274I2632J-2312D01*
G02X894510Y388973I-2J-3503D01*
G03X894672I81J183D01*
G02X896091Y389274I1421J-3202D01*
G02Y382268I0J-3503D01*
G02X894672Y382569I2J3503D01*
G03X894510I-81J-183D01*
G02X893091Y382268I-1421J3202D01*
G02X890460Y383459I1J3503D01*
G01X890431Y383492D01*
X890353Y383527D01*
X889966D01*
X889888Y383492D01*
X889859Y383459D01*
G02X887228Y382268I-2632J2312D01*
G02X885809Y382569I2J3503D01*
G03X885647I-81J-183D01*
G02X884228Y382268I-1421J3202D01*
G02X881166Y384070I0J3503D01*
G03X880991Y384173I-175J-97D01*
G01X880642D01*
G03X880467Y384070I0J-200D01*
G02X877405Y382268I-3062J1701D01*
G02X875986Y382569I2J3503D01*
G03X875824I-81J-183D01*
G02X874405Y382268I-1421J3202D01*
G02X871774Y383459I1J3503D01*
G01X871745Y383492D01*
X871667Y383527D01*
X871280D01*
X871202Y383492D01*
X871173Y383459D01*
G02X868542Y382268I-2632J2312D01*
G02X867123Y382569I2J3503D01*
G03X866961I-81J-183D01*
G02X865542Y382268I-1421J3202D01*
G02X862685Y383746I1J3502D01*
G01X862657Y383785D01*
X862573Y383829D01*
X862154Y383836D01*
X862069Y383795D01*
X862040Y383757D01*
G02X859253Y382376I-2787J2122D01*
G02X857834Y382676I-1J3502D01*
G03X857672I-81J-183D01*
G02X856253Y382376I-1418J3202D01*
G02X853622Y383566I-1J3502D01*
G01X853593Y383599D01*
X853515Y383634D01*
X853128D01*
X853050Y383599D01*
X853021Y383566D01*
G02X850390Y382376I-2630J2312D01*
G02X848971Y382676I-1J3502D01*
G03X848809I-81J-183D01*
G02X847390Y382376I-1418J3202D01*
G02Y389380I0J3502D01*
G02X848809Y389080I1J-3502D01*
G03X848971I81J183D01*
G02X850390Y389380I1418J-3202D01*
G02X853021Y388190I1J-3502D01*
G01X853050Y388157D01*
X853128Y388122D01*
G37*
G36*
G01X1071582Y404036D02*
X1071738Y404469D01*
X1071718Y404575D01*
X1071682Y404617D01*
G02X1070814Y406925I2634J2308D01*
G02X1077818I3502J0D01*
G02X1074872Y403467I-3502J0D01*
G01X1074817Y403458D01*
X1074734Y403389D01*
X1074578Y402956D01*
X1074598Y402850D01*
X1074634Y402808D01*
G02X1075502Y400500I-2634J-2308D01*
G02X1075202Y399081I-3502J-1D01*
G03Y398919I183J-81D01*
G02X1075502Y397500I-3202J-1418D01*
G02X1072000Y393998I-3502J0D01*
G02X1070581Y394298I-1J3502D01*
G03X1070419I-81J-183D01*
G02X1069611Y394051I-1420J3202D01*
G03X1069449Y393889I35J-197D01*
G02X1069202Y393081I-3449J612D01*
G03Y392919I183J-81D01*
G02X1069449Y392111I-3202J-1420D01*
G03X1069611Y391949I197J35D01*
G02X1070419Y391702I-612J-3449D01*
G03X1070581I81J183D01*
G02X1072000Y392002I1418J-3202D01*
G02X1075502Y388500I0J-3502D01*
G02X1075202Y387081I-3502J-1D01*
G03Y386919I183J-81D01*
G02X1075502Y385500I-3202J-1418D01*
G02X1072000Y381998I-3502J0D01*
G02X1070581Y382298I-1J3502D01*
G03X1070419I-81J-183D01*
G02X1069000Y381998I-1418J3202D01*
G02X1067581Y382298I-1J3502D01*
G03X1067419I-81J-183D01*
G02X1066000Y381998I-1418J3202D01*
G02X1064581Y382298I-1J3502D01*
G03X1064419I-81J-183D01*
G02X1063000Y381998I-1418J3202D01*
G02X1061581Y382298I-1J3502D01*
G03X1061419I-81J-183D01*
G02X1060000Y381998I-1418J3202D01*
G02X1056498Y385500I0J3502D01*
G02X1056798Y386919I3502J1D01*
G03Y387081I-183J81D01*
G02X1056498Y388500I3202J1418D01*
G02X1056798Y389919I3502J1D01*
G03Y390081I-183J81D01*
G02X1056498Y391500I3202J1418D01*
G02X1056798Y392919I3502J1D01*
G03Y393081I-183J81D01*
G02X1056498Y394500I3202J1418D01*
G02X1056798Y395919I3502J1D01*
G03Y396081I-183J81D01*
G02X1056498Y397500I3202J1418D01*
G02X1056798Y398919I3502J1D01*
G03Y399081I-183J81D01*
G02X1056498Y400500I3202J1418D01*
G02X1060000Y404002I3502J0D01*
G02X1061419Y403702I1J-3502D01*
G03X1061581I81J183D01*
G02X1063000Y404002I1418J-3202D01*
G02X1064419Y403702I1J-3502D01*
G03X1064581I81J183D01*
G02X1066000Y404002I1418J-3202D01*
G02X1067419Y403702I1J-3502D01*
G03X1067581I81J183D01*
G02X1069000Y404002I1418J-3202D01*
G02X1070419Y403702I1J-3502D01*
G03X1070581I81J183D01*
G02X1071444Y403958I1419J-3202D01*
G01X1071499Y403967D01*
X1071582Y404036D01*
G37*
G36*
G01X806904Y420118D02*
G02X808323Y420418I1418J-3202D01*
G02X809742Y420118I1J-3502D01*
G03X809904I81J183D01*
G02X811323Y420418I1418J-3202D01*
G02X812742Y420118I1J-3502D01*
G03X812904I81J183D01*
G02X814323Y420418I1418J-3202D01*
G02X815723Y420126I0J-3502D01*
G03X815876Y420123I80J184D01*
G02X817153Y420364I1277J-3261D01*
G02X820656Y416862I1J-3502D01*
G02X820355Y415443I-3503J2D01*
G03Y415281I183J-81D01*
G02X820656Y413862I-3202J-1421D01*
G02X820402Y412554I-3503J2D01*
G03Y412404I186J-75D01*
G02X820656Y411096I-3249J-1310D01*
G02X820355Y409677I-3503J2D01*
G03Y409515I183J-81D01*
G02X820656Y408096I-3202J-1421D01*
G02X820355Y406677I-3503J2D01*
G03Y406515I183J-81D01*
G02X820656Y405096I-3202J-1421D01*
G02X817153Y401594I-3503J1D01*
G02X815753Y401886I0J3502D01*
G03X815600Y401889I-80J-184D01*
G02X814323Y401648I-1277J3261D01*
G02X812904Y401948I-1J3502D01*
G03X812742I-81J-183D01*
G02X811323Y401648I-1418J3202D01*
G02X809904Y401948I-1J3502D01*
G03X809742I-81J-183D01*
G02X808323Y401648I-1418J3202D01*
G02X806904Y401948I-1J3502D01*
G03X806742I-81J-183D01*
G02X805323Y401648I-1418J3202D01*
G02X803904Y401948I-1J3502D01*
G03X803742I-81J-183D01*
G02X802323Y401648I-1418J3202D01*
G02X800904Y401948I-1J3502D01*
G03X800742I-81J-183D01*
G02X799323Y401648I-1418J3202D01*
G02X798098Y401869I-1J3502D01*
G03X797951Y401866I-70J-188D01*
G02X796600Y401594I-1353J3231D01*
G02X793098Y405097I1J3503D01*
G02X793398Y406516I3502J1D01*
G03Y406678I-183J81D01*
G02X793098Y408097I3202J1418D01*
G02X793398Y409516I3502J1D01*
G03Y409678I-183J81D01*
G02X793098Y411097I3202J1418D01*
G02X793351Y412405I3502J1D01*
G03Y412555I-186J75D01*
G02X793098Y413863I3249J1307D01*
G02X793398Y415282I3502J1D01*
G03Y415444I-183J81D01*
G02X793098Y416863I3202J1418D01*
G02X796600Y420366I3502J1D01*
G02X797825Y420144I-2J-3503D01*
G03X797972Y420147I70J188D01*
G02X799323Y420418I1351J-3232D01*
G02X800742Y420118I1J-3502D01*
G03X800904I81J183D01*
G02X802323Y420418I1418J-3202D01*
G02X803742Y420118I1J-3502D01*
G03X803904I81J183D01*
G02X805323Y420418I1418J-3202D01*
G02X806742Y420118I1J-3502D01*
G03X806904I81J183D01*
G37*
G36*
G01X863923D02*
G02X865342Y420418I1418J-3202D01*
G02X866761Y420118I1J-3502D01*
G03X866923I81J183D01*
G02X868342Y420418I1418J-3202D01*
G02X869761Y420118I1J-3502D01*
G03X869923I81J183D01*
G02X871342Y420418I1418J-3202D01*
G02X872742Y420126I0J-3502D01*
G03X872895Y420123I80J184D01*
G02X874172Y420364I1277J-3261D01*
G02X877674Y416862I0J-3502D01*
G02X877374Y415443I-3502J-1D01*
G03Y415281I183J-81D01*
G02X877674Y413862I-3202J-1418D01*
G02X877421Y412554I-3502J-1D01*
G03Y412404I186J-75D01*
G02X877674Y411096I-3249J-1307D01*
G02X877374Y409677I-3502J-1D01*
G03Y409515I183J-81D01*
G02X877674Y408096I-3202J-1418D01*
G02X877374Y406677I-3502J-1D01*
G03Y406515I183J-81D01*
G02X877674Y405096I-3202J-1418D01*
G02X874172Y401594I-3502J0D01*
G02X872772Y401886I0J3502D01*
G03X872619Y401889I-80J-184D01*
G02X871342Y401648I-1277J3261D01*
G02X869923Y401948I-1J3502D01*
G03X869761I-81J-183D01*
G02X868342Y401648I-1418J3202D01*
G02X866923Y401948I-1J3502D01*
G03X866761I-81J-183D01*
G02X865342Y401648I-1418J3202D01*
G02X863923Y401948I-1J3502D01*
G03X863761I-81J-183D01*
G02X862342Y401648I-1418J3202D01*
G02X860923Y401948I-1J3502D01*
G03X860761I-81J-183D01*
G02X859342Y401648I-1418J3202D01*
G02X857923Y401948I-1J3502D01*
G03X857761I-81J-183D01*
G02X856342Y401648I-1418J3202D01*
G02X855117Y401869I-1J3502D01*
G03X854970Y401866I-70J-188D01*
G02X853619Y401594I-1353J3231D01*
G02X850116Y405097I0J3503D01*
G02X850417Y406516I3503J-2D01*
G03Y406678I-183J81D01*
G02X850116Y408097I3202J1421D01*
G02X850417Y409516I3503J-2D01*
G03Y409678I-183J81D01*
G02X850116Y411097I3202J1421D01*
G02X850370Y412405I3503J-2D01*
G03Y412555I-186J75D01*
G02X850116Y413863I3249J1310D01*
G02X850417Y415282I3503J-2D01*
G03Y415444I-183J81D01*
G02X850116Y416863I3202J1421D01*
G02X853619Y420366I3503J0D01*
G02X854844Y420144I-2J-3503D01*
G03X854991Y420147I70J188D01*
G02X856342Y420418I1351J-3232D01*
G02X857761Y420118I1J-3502D01*
G03X857923I81J183D01*
G02X859342Y420418I1418J-3202D01*
G02X860761Y420118I1J-3502D01*
G03X860923I81J183D01*
G02X862342Y420418I1418J-3202D01*
G02X863761Y420118I1J-3502D01*
G03X863923I81J183D01*
G37*
G36*
G01X112520Y422234D02*
G02X112198Y423700I3180J1467D01*
G02X112498Y425119I3502J1D01*
G03Y425281I-182J81D01*
G02X112198Y426700I3202J1418D01*
G02X115700Y430202I3502J0D01*
G02X117576Y429657I0J-3501D01*
G03X117782Y429651I108J169D01*
G02X119500Y430102I1719J-3051D01*
G02X121155Y429686I0J-3502D01*
G03X121345I95J176D01*
G02X123000Y430102I1655J-3086D01*
G02X126502Y426600I0J-3502D01*
G02X126202Y425181I-3502J-1D01*
G03Y425019I182J-81D01*
G02X126502Y423600I-3202J-1418D01*
G02X126181Y422134I-3502J-1D01*
G03Y421967I181J-84D01*
G02X126502Y420500I-3181J-1465D01*
G02X126202Y419081I-3502J-1D01*
G03Y418919I183J-81D01*
G02X126502Y417500I-3202J-1418D01*
G02X126202Y416081I-3502J-1D01*
G03Y415919I183J-81D01*
G02X126502Y414500I-3202J-1418D01*
G02X126202Y413081I-3502J-1D01*
G03Y412919I183J-81D01*
G02X126502Y411500I-3202J-1418D01*
G02X126202Y410081I-3502J-1D01*
G03Y409919I183J-81D01*
G02X126502Y408500I-3202J-1418D01*
G02X123000Y404998I-3502J0D01*
G02X121345Y405413I-1J3502D01*
G03X121155I-95J-176D01*
G02X119500Y404998I-1654J3087D01*
G02X117623Y405543I-1J3502D01*
G03X117418Y405548I-107J-169D01*
G02X115700Y405098I-1717J3052D01*
G02X112198Y408600I0J3502D01*
G02X112498Y410019I3502J1D01*
G03Y410181I-182J81D01*
G02X112198Y411600I3202J1418D01*
G02X112498Y413019I3502J1D01*
G03Y413181I-182J81D01*
G02X112198Y414600I3202J1418D01*
G02X112498Y416019I3502J1D01*
G03Y416181I-182J81D01*
G02X112198Y417600I3202J1418D01*
G02X112498Y419019I3502J1D01*
G03Y419181I-182J81D01*
G02X112198Y420600I3202J1418D01*
G02X112520Y422066I3502J-1D01*
G03Y422234I-182J84D01*
G37*
G36*
G01X153598Y425181D02*
G02X153298Y426600I3202J1418D01*
G02X156800Y430102I3502J0D01*
G02X158455Y429686I0J-3502D01*
G03X158645I95J176D01*
G02X160300Y430102I1655J-3086D01*
G02X161867Y429732I0J-3503D01*
G03X162056Y429737I90J179D01*
G02X163800Y430202I1744J-3038D01*
G02X167302Y426700I0J-3502D01*
G02X167002Y425281I-3502J-1D01*
G03Y425119I182J-81D01*
G02X167302Y423700I-3202J-1418D01*
G02X167067Y422438I-3502J-1D01*
G03X167078Y422271I187J-72D01*
G02X167502Y420600I-3078J-1670D01*
G02X167202Y419181I-3502J-1D01*
G03Y419019I182J-81D01*
G02X167502Y417600I-3202J-1418D01*
G02X167202Y416181I-3502J-1D01*
G03Y416019I182J-81D01*
G02X167502Y414600I-3202J-1418D01*
G02X167202Y413181I-3502J-1D01*
G03Y413019I182J-81D01*
G02X167502Y411600I-3202J-1418D01*
G02X167202Y410181I-3502J-1D01*
G03Y410019I182J-81D01*
G02X167502Y408600I-3202J-1418D01*
G02X164000Y405098I-3502J0D01*
G02X162433Y405468I0J3503D01*
G03X162244Y405463I-90J-179D01*
G02X160500Y404998I-1744J3038D01*
G02X158845Y405413I-1J3502D01*
G03X158655I-95J-176D01*
G02X157000Y404998I-1654J3087D01*
G02X153498Y408500I0J3502D01*
G02X153798Y409919I3502J1D01*
G03Y410081I-183J81D01*
G02X153498Y411500I3202J1418D01*
G02X153798Y412919I3502J1D01*
G03Y413081I-183J81D01*
G02X153498Y414500I3202J1418D01*
G02X153798Y415919I3502J1D01*
G03Y416081I-183J81D01*
G02X153498Y417500I3202J1418D01*
G02X153798Y418919I3502J1D01*
G03Y419081I-183J81D01*
G02X153498Y420500I3202J1418D01*
G02X153733Y421762I3502J1D01*
G03X153722Y421930I-187J72D01*
G02X153298Y423600I3077J1670D01*
G02X153598Y425019I3502J1D01*
G03Y425181I-182J81D01*
G37*
G36*
G01X563318Y445297D02*
G02X564500Y445502I1181J-3297D01*
G02Y438498I0J-3502D01*
G02X563318Y438703I-1J3502D01*
G03X563182I-68J-188D01*
G02X562000Y438498I-1181J3297D01*
G02Y445502I0J3502D01*
G02X563182Y445297I1J-3502D01*
G03X563318I68J188D01*
G37*
G36*
G01X1064581Y451202D02*
G02X1066000Y451502I1418J-3202D01*
G02X1067419Y451202I1J-3502D01*
G03X1067581I81J183D01*
G02X1069000Y451502I1418J-3202D01*
G02X1070419Y451202I1J-3502D01*
G03X1070581I81J183D01*
G02X1072000Y451502I1418J-3202D01*
G02X1075502Y448000I0J-3502D01*
G02X1075202Y446581I-3502J-1D01*
G03Y446419I183J-81D01*
G02X1075502Y445000I-3202J-1418D01*
G02X1072000Y441498I-3502J0D01*
G02X1070581Y441798I-1J3502D01*
G03X1070419I-81J-183D01*
G02X1069611Y441551I-1420J3202D01*
G03X1069449Y441389I35J-197D01*
G02X1069202Y440581I-3449J612D01*
G03Y440419I183J-81D01*
G02X1069449Y439611I-3202J-1420D01*
G03X1069611Y439449I197J35D01*
G02X1070419Y439202I-612J-3449D01*
G03X1070581I81J183D01*
G02X1072000Y439502I1418J-3202D01*
G02X1075502Y436000I0J-3502D01*
G02X1075202Y434581I-3502J-1D01*
G03Y434419I183J-81D01*
G02X1075502Y433000I-3202J-1418D01*
G02X1072000Y429498I-3502J0D01*
G02X1070581Y429798I-1J3502D01*
G03X1070419I-81J-183D01*
G02X1069000Y429498I-1418J3202D01*
G02X1067581Y429798I-1J3502D01*
G03X1067419I-81J-183D01*
G02X1066000Y429498I-1418J3202D01*
G02X1064581Y429798I-1J3502D01*
G03X1064419I-81J-183D01*
G02X1063000Y429498I-1418J3202D01*
G02X1061581Y429798I-1J3502D01*
G03X1061419I-81J-183D01*
G02X1060000Y429498I-1418J3202D01*
G02X1056498Y433000I0J3502D01*
G02X1056798Y434419I3502J1D01*
G03Y434581I-183J81D01*
G02X1056498Y436000I3202J1418D01*
G02X1056798Y437419I3502J1D01*
G03Y437581I-183J81D01*
G02X1056498Y439000I3202J1418D01*
G02X1056798Y440419I3502J1D01*
G03Y440581I-183J81D01*
G02X1056498Y442000I3202J1418D01*
G02X1056798Y443419I3502J1D01*
G03Y443581I-183J81D01*
G02X1056498Y445000I3202J1418D01*
G02X1056798Y446419I3502J1D01*
G03Y446581I-183J81D01*
G02X1056498Y448000I3202J1418D01*
G02X1060000Y451502I3502J0D01*
G02X1061419Y451202I1J-3502D01*
G03X1061581I81J183D01*
G02X1063000Y451502I1418J-3202D01*
G02X1064419Y451202I1J-3502D01*
G03X1064581I81J183D01*
G37*
G36*
G01X810290Y489534D02*
G02X811709Y489834I1418J-3202D01*
G02X813128Y489534I1J-3502D01*
G03X813290I81J183D01*
G02X814709Y489834I1418J-3202D01*
G02X816128Y489534I1J-3502D01*
G03X816290I81J183D01*
G02X817709Y489834I1418J-3202D01*
G02X821212Y486332I1J-3502D01*
G02X820920Y484932I-3502J0D01*
G03X820917Y484779I183J-80D01*
G02X821158Y483503I-3262J-1277D01*
G02X820857Y482084I-3503J2D01*
G03Y481922I183J-81D01*
G02X821158Y480503I-3202J-1421D01*
G02X820894Y479170I-3503J1D01*
G03Y479017I185J-76D01*
G02X821158Y477684I-3239J-1334D01*
G02X820857Y476265I-3503J2D01*
G03Y476103I183J-81D01*
G02X821158Y474684I-3202J-1421D01*
G02X817655Y471182I-3503J1D01*
G02X816236Y471482I-1J3502D01*
G03X816074I-81J-183D01*
G02X814655Y471182I-1418J3202D01*
G02X813236Y471482I-1J3502D01*
G03X813074I-81J-183D01*
G02X811655Y471182I-1418J3202D01*
G02X810236Y471482I-1J3502D01*
G03X810074I-81J-183D01*
G02X808655Y471182I-1418J3202D01*
G02X807236Y471482I-1J3502D01*
G03X807074I-81J-183D01*
G02X805655Y471182I-1418J3202D01*
G02X804236Y471482I-1J3502D01*
G03X804074I-81J-183D01*
G02X802655Y471182I-1418J3202D01*
G02X801236Y471482I-1J3502D01*
G03X801074I-81J-183D01*
G02X799655Y471182I-1418J3202D01*
G02X798236Y471482I-1J3502D01*
G03X798074I-81J-183D01*
G02X796655Y471182I-1418J3202D01*
G02X793152Y474684I-1J3502D01*
G02X793453Y476103I3503J-2D01*
G03Y476265I-183J81D01*
G02X793152Y477684I3202J1421D01*
G02X793416Y479017I3503J-1D01*
G03Y479170I-185J77D01*
G02X793152Y480503I3239J1334D01*
G02X793453Y481922I3503J-2D01*
G03Y482084I-183J81D01*
G02X793152Y483503I3202J1421D01*
G02X793444Y484903I3502J0D01*
G03X793447Y485056I-183J80D01*
G02X793206Y486332I3262J1277D01*
G02X796709Y489834I3503J-1D01*
G02X798128Y489534I1J-3502D01*
G03X798290I81J183D01*
G02X799709Y489834I1418J-3202D01*
G02X801128Y489534I1J-3502D01*
G03X801290I81J183D01*
G02X802709Y489834I1418J-3202D01*
G02X804128Y489534I1J-3502D01*
G03X804290I81J183D01*
G02X805709Y489834I1418J-3202D01*
G02X807128Y489534I1J-3502D01*
G03X807290I81J183D01*
G02X808709Y489834I1418J-3202D01*
G02X810128Y489534I1J-3502D01*
G03X810290I81J183D01*
G37*
G36*
G01X866892D02*
G02X868311Y489834I1418J-3202D01*
G02X869730Y489534I1J-3502D01*
G03X869892I81J183D01*
G02X871311Y489834I1418J-3202D01*
G02X872730Y489534I1J-3502D01*
G03X872892I81J183D01*
G02X874311Y489834I1418J-3202D01*
G02X877814Y486332I1J-3502D01*
G02X877522Y484932I-3502J0D01*
G03X877519Y484779I183J-80D01*
G02X877760Y483503I-3262J-1277D01*
G02X877459Y482084I-3503J2D01*
G03Y481922I183J-81D01*
G02X877760Y480503I-3202J-1421D01*
G02X877496Y479170I-3503J1D01*
G03Y479017I185J-76D01*
G02X877760Y477684I-3239J-1334D01*
G02X877459Y476265I-3503J2D01*
G03Y476103I183J-81D01*
G02X877760Y474684I-3202J-1421D01*
G02X874257Y471182I-3503J1D01*
G02X872838Y471482I-1J3502D01*
G03X872676I-81J-183D01*
G02X871257Y471182I-1418J3202D01*
G02X869838Y471482I-1J3502D01*
G03X869676I-81J-183D01*
G02X868257Y471182I-1418J3202D01*
G02X866838Y471482I-1J3502D01*
G03X866676I-81J-183D01*
G02X865257Y471182I-1418J3202D01*
G02X863838Y471482I-1J3502D01*
G03X863676I-81J-183D01*
G02X862257Y471182I-1418J3202D01*
G02X860838Y471482I-1J3502D01*
G03X860676I-81J-183D01*
G02X859257Y471182I-1418J3202D01*
G02X857838Y471482I-1J3502D01*
G03X857676I-81J-183D01*
G02X856257Y471182I-1418J3202D01*
G02X854838Y471482I-1J3502D01*
G03X854676I-81J-183D01*
G02X853257Y471182I-1418J3202D01*
G02X849754Y474684I-1J3502D01*
G02X850055Y476103I3503J-2D01*
G03Y476265I-183J81D01*
G02X849754Y477684I3202J1421D01*
G02X850018Y479017I3503J-1D01*
G03Y479170I-185J77D01*
G02X849754Y480503I3239J1334D01*
G02X850055Y481922I3503J-2D01*
G03Y482084I-183J81D01*
G02X849754Y483503I3202J1421D01*
G02X850046Y484903I3502J0D01*
G03X850049Y485056I-183J80D01*
G02X849808Y486332I3262J1277D01*
G02X853311Y489834I3503J-1D01*
G02X854730Y489534I1J-3502D01*
G03X854892I81J183D01*
G02X856311Y489834I1418J-3202D01*
G02X857730Y489534I1J-3502D01*
G03X857892I81J183D01*
G02X859311Y489834I1418J-3202D01*
G02X860730Y489534I1J-3502D01*
G03X860892I81J183D01*
G02X862311Y489834I1418J-3202D01*
G02X863730Y489534I1J-3502D01*
G03X863892I81J183D01*
G02X865311Y489834I1418J-3202D01*
G02X866730Y489534I1J-3502D01*
G03X866892I81J183D01*
G37*
G36*
G01X68400Y475573D02*
X67972Y475638D01*
X67879Y475606D01*
X67844Y475568D01*
G02Y488842I-7214J6637D01*
G01X67879Y488804D01*
X67972Y488772D01*
X68400Y488837D01*
X68479Y488896D01*
X68500Y488942D01*
G02X82795Y498008I14295J-6737D01*
G02Y466402I0J-15803D01*
G02X68500Y475468I0J15803D01*
G01X68479Y475514D01*
X68400Y475573D01*
G37*
G36*
G01X1064581Y498702D02*
G02X1066000Y499002I1418J-3202D01*
G02X1067419Y498702I1J-3502D01*
G03X1067581I81J183D01*
G02X1069000Y499002I1418J-3202D01*
G02X1070419Y498702I1J-3502D01*
G03X1070581I81J183D01*
G02X1072000Y499002I1418J-3202D01*
G02X1075502Y495500I0J-3502D01*
G02X1075202Y494081I-3502J-1D01*
G03Y493919I183J-81D01*
G02X1075502Y492500I-3202J-1418D01*
G02X1072000Y488998I-3502J0D01*
G02X1070581Y489298I-1J3502D01*
G03X1070419I-81J-183D01*
G02X1069611Y489051I-1420J3202D01*
G03X1069449Y488889I35J-197D01*
G02X1069202Y488081I-3449J612D01*
G03Y487919I183J-81D01*
G02X1069449Y487111I-3202J-1420D01*
G03X1069611Y486949I197J35D01*
G02X1070419Y486702I-612J-3449D01*
G03X1070581I81J183D01*
G02X1072000Y487002I1418J-3202D01*
G02X1075502Y483500I0J-3502D01*
G02X1075202Y482081I-3502J-1D01*
G03Y481919I183J-81D01*
G02X1075502Y480500I-3202J-1418D01*
G02X1072000Y476998I-3502J0D01*
G02X1070581Y477298I-1J3502D01*
G03X1070419I-81J-183D01*
G02X1069000Y476998I-1418J3202D01*
G02X1067581Y477298I-1J3502D01*
G03X1067419I-81J-183D01*
G02X1066000Y476998I-1418J3202D01*
G02X1064581Y477298I-1J3502D01*
G03X1064419I-81J-183D01*
G02X1063000Y476998I-1418J3202D01*
G02X1061581Y477298I-1J3502D01*
G03X1061419I-81J-183D01*
G02X1060000Y476998I-1418J3202D01*
G02X1056498Y480500I0J3502D01*
G02X1056798Y481919I3502J1D01*
G03Y482081I-183J81D01*
G02X1056498Y483500I3202J1418D01*
G02X1056798Y484919I3502J1D01*
G03Y485081I-183J81D01*
G02X1056498Y486500I3202J1418D01*
G02X1056798Y487919I3502J1D01*
G03Y488081I-183J81D01*
G02X1056498Y489500I3202J1418D01*
G02X1056798Y490919I3502J1D01*
G03Y491081I-183J81D01*
G02X1056498Y492500I3202J1418D01*
G02X1056798Y493919I3502J1D01*
G03Y494081I-183J81D01*
G02X1056498Y495500I3202J1418D01*
G02X1060000Y499002I3502J0D01*
G02X1061419Y498702I1J-3502D01*
G03X1061581I81J183D01*
G02X1063000Y499002I1418J-3202D01*
G02X1064419Y498702I1J-3502D01*
G03X1064581I81J183D01*
G37*
G36*
G01X170520Y501202D02*
G02X171939Y501502I1418J-3202D01*
G02Y494498I0J-3502D01*
G02X170520Y494798I-1J3502D01*
G03X170358I-81J-183D01*
G02X168939Y494498I-1418J3202D01*
G02Y501502I0J3502D01*
G02X170358Y501202I1J-3502D01*
G03X170520I81J183D01*
G37*
G36*
G01X218520D02*
G02X219939Y501502I1418J-3202D01*
G02Y494498I0J-3502D01*
G02X218520Y494798I-1J3502D01*
G03X218358I-81J-183D01*
G02X216939Y494498I-1418J3202D01*
G02Y501502I0J3502D01*
G02X218358Y501202I1J-3502D01*
G03X218520I81J183D01*
G37*
G36*
G01X266520D02*
G02X267939Y501502I1418J-3202D01*
G02Y494498I0J-3502D01*
G02X266520Y494798I-1J3502D01*
G03X266358I-81J-183D01*
G02X264939Y494498I-1418J3202D01*
G02Y501502I0J3502D01*
G02X266358Y501202I1J-3502D01*
G03X266520I81J183D01*
G37*
G36*
G01X328000D02*
G02X329419Y501502I1418J-3202D01*
G02Y494498I0J-3502D01*
G02X328000Y494798I-1J3502D01*
G03X327838I-81J-183D01*
G02X326419Y494498I-1418J3202D01*
G02Y501502I0J3502D01*
G02X327838Y501202I1J-3502D01*
G03X328000I81J183D01*
G37*
G36*
G01X376000D02*
G02X377419Y501502I1418J-3202D01*
G02Y494498I0J-3502D01*
G02X376000Y494798I-1J3502D01*
G03X375838I-81J-183D01*
G02X374419Y494498I-1418J3202D01*
G02Y501502I0J3502D01*
G02X375838Y501202I1J-3502D01*
G03X376000I81J183D01*
G37*
G36*
G01X424000D02*
G02X425419Y501502I1418J-3202D01*
G02Y494498I0J-3502D01*
G02X424000Y494798I-1J3502D01*
G03X423838I-81J-183D01*
G02X422419Y494498I-1418J3202D01*
G02Y501502I0J3502D01*
G02X423838Y501202I1J-3502D01*
G03X424000I81J183D01*
G37*
G36*
G01X485481D02*
G02X486900Y501502I1418J-3202D01*
G02Y494498I0J-3502D01*
G02X485481Y494798I-1J3502D01*
G03X485319I-81J-183D01*
G02X483900Y494498I-1418J3202D01*
G02Y501502I0J3502D01*
G02X485319Y501202I1J-3502D01*
G03X485481I81J183D01*
G37*
G36*
G01X533481D02*
G02X534900Y501502I1418J-3202D01*
G02Y494498I0J-3502D01*
G02X533481Y494798I-1J3502D01*
G03X533319I-81J-183D01*
G02X531900Y494498I-1418J3202D01*
G02Y501502I0J3502D01*
G02X533319Y501202I1J-3502D01*
G03X533481I81J183D01*
G37*
G36*
G01X581481D02*
G02X582900Y501502I1418J-3202D01*
G02Y494498I0J-3502D01*
G02X581481Y494798I-1J3502D01*
G03X581319I-81J-183D01*
G02X579900Y494498I-1418J3202D01*
G02Y501502I0J3502D01*
G02X581319Y501202I1J-3502D01*
G03X581481I81J183D01*
G37*
G36*
G01X642962D02*
G02X644381Y501502I1418J-3202D01*
G02Y494498I0J-3502D01*
G02X642962Y494798I-1J3502D01*
G03X642800I-81J-183D01*
G02X641381Y494498I-1418J3202D01*
G02Y501502I0J3502D01*
G02X642800Y501202I1J-3502D01*
G03X642962I81J183D01*
G37*
G36*
G01X690962D02*
G02X692381Y501502I1418J-3202D01*
G02Y494498I0J-3502D01*
G02X690962Y494798I-1J3502D01*
G03X690800I-81J-183D01*
G02X689381Y494498I-1418J3202D01*
G02Y501502I0J3502D01*
G02X690800Y501202I1J-3502D01*
G03X690962I81J183D01*
G37*
G36*
G01X738962D02*
G02X740381Y501502I1418J-3202D01*
G02Y494498I0J-3502D01*
G02X738962Y494798I-1J3502D01*
G03X738800I-81J-183D01*
G02X737381Y494498I-1418J3202D01*
G02Y501502I0J3502D01*
G02X738800Y501202I1J-3502D01*
G03X738962I81J183D01*
G37*
G36*
G01X170520Y521202D02*
G02X171939Y521502I1418J-3202D01*
G02Y514498I0J-3502D01*
G02X170520Y514798I-1J3502D01*
G03X170358I-81J-183D01*
G02X168939Y514498I-1418J3202D01*
G02Y521502I0J3502D01*
G02X170358Y521202I1J-3502D01*
G03X170520I81J183D01*
G37*
G36*
G01X218520D02*
G02X219939Y521502I1418J-3202D01*
G02Y514498I0J-3502D01*
G02X218520Y514798I-1J3502D01*
G03X218358I-81J-183D01*
G02X216939Y514498I-1418J3202D01*
G02Y521502I0J3502D01*
G02X218358Y521202I1J-3502D01*
G03X218520I81J183D01*
G37*
G36*
G01X266520D02*
G02X267939Y521502I1418J-3202D01*
G02Y514498I0J-3502D01*
G02X266520Y514798I-1J3502D01*
G03X266358I-81J-183D01*
G02X264939Y514498I-1418J3202D01*
G02Y521502I0J3502D01*
G02X266358Y521202I1J-3502D01*
G03X266520I81J183D01*
G37*
G36*
G01X328000D02*
G02X329419Y521502I1418J-3202D01*
G02Y514498I0J-3502D01*
G02X328000Y514798I-1J3502D01*
G03X327838I-81J-183D01*
G02X326419Y514498I-1418J3202D01*
G02Y521502I0J3502D01*
G02X327838Y521202I1J-3502D01*
G03X328000I81J183D01*
G37*
G36*
G01X376000D02*
G02X377419Y521502I1418J-3202D01*
G02Y514498I0J-3502D01*
G02X376000Y514798I-1J3502D01*
G03X375838I-81J-183D01*
G02X374419Y514498I-1418J3202D01*
G02Y521502I0J3502D01*
G02X375838Y521202I1J-3502D01*
G03X376000I81J183D01*
G37*
G36*
G01X424000D02*
G02X425419Y521502I1418J-3202D01*
G02Y514498I0J-3502D01*
G02X424000Y514798I-1J3502D01*
G03X423838I-81J-183D01*
G02X422419Y514498I-1418J3202D01*
G02Y521502I0J3502D01*
G02X423838Y521202I1J-3502D01*
G03X424000I81J183D01*
G37*
G36*
G01X485481D02*
G02X486900Y521502I1418J-3202D01*
G02Y514498I0J-3502D01*
G02X485481Y514798I-1J3502D01*
G03X485319I-81J-183D01*
G02X483900Y514498I-1418J3202D01*
G02Y521502I0J3502D01*
G02X485319Y521202I1J-3502D01*
G03X485481I81J183D01*
G37*
G36*
G01X533481D02*
G02X534900Y521502I1418J-3202D01*
G02Y514498I0J-3502D01*
G02X533481Y514798I-1J3502D01*
G03X533319I-81J-183D01*
G02X531900Y514498I-1418J3202D01*
G02Y521502I0J3502D01*
G02X533319Y521202I1J-3502D01*
G03X533481I81J183D01*
G37*
G36*
G01X581481D02*
G02X582900Y521502I1418J-3202D01*
G02Y514498I0J-3502D01*
G02X581481Y514798I-1J3502D01*
G03X581319I-81J-183D01*
G02X579900Y514498I-1418J3202D01*
G02Y521502I0J3502D01*
G02X581319Y521202I1J-3502D01*
G03X581481I81J183D01*
G37*
G36*
G01X642962D02*
G02X644381Y521502I1418J-3202D01*
G02Y514498I0J-3502D01*
G02X642962Y514798I-1J3502D01*
G03X642800I-81J-183D01*
G02X641381Y514498I-1418J3202D01*
G02Y521502I0J3502D01*
G02X642800Y521202I1J-3502D01*
G03X642962I81J183D01*
G37*
G36*
G01X690962D02*
G02X692381Y521502I1418J-3202D01*
G02Y514498I0J-3502D01*
G02X690962Y514798I-1J3502D01*
G03X690800I-81J-183D01*
G02X689381Y514498I-1418J3202D01*
G02Y521502I0J3502D01*
G02X690800Y521202I1J-3502D01*
G03X690962I81J183D01*
G37*
G36*
G01X738962D02*
G02X740381Y521502I1418J-3202D01*
G02Y514498I0J-3502D01*
G02X738962Y514798I-1J3502D01*
G03X738800I-81J-183D01*
G02X737381Y514498I-1418J3202D01*
G02Y521502I0J3502D01*
G02X738800Y521202I1J-3502D01*
G03X738962I81J183D01*
G37*
G36*
G01X916288Y522263D02*
G02X917596Y522516I1307J-3249D01*
G02X919015Y522216I1J-3502D01*
G03X919177I81J183D01*
G02X920596Y522516I1418J-3202D01*
G02X922015Y522216I1J-3502D01*
G03X922177I81J183D01*
G02X923596Y522516I1418J-3202D01*
G02X927098Y519014I0J-3502D01*
G02X926806Y517614I-3502J0D01*
G03X926803Y517461I184J-80D01*
G02X927044Y516184I-3261J-1277D01*
G02X926744Y514765I-3502J-1D01*
G03Y514603I183J-81D01*
G02X927044Y513184I-3202J-1418D01*
G02X926744Y511765I-3502J-1D01*
G03Y511603I183J-81D01*
G02X927044Y510184I-3202J-1418D01*
G02X926744Y508765I-3502J-1D01*
G03Y508603I183J-81D01*
G02X927044Y507184I-3202J-1418D01*
G02X926744Y505765I-3502J-1D01*
G03Y505603I183J-81D01*
G02X927044Y504184I-3202J-1418D01*
G02X926744Y502765I-3502J-1D01*
G03Y502603I183J-81D01*
G02X927044Y501184I-3202J-1418D01*
G02X926823Y499959I-3502J-1D01*
G03X926826Y499812I188J-70D01*
G02X927098Y498461I-3231J-1353D01*
G02X923595Y494958I-3503J0D01*
G02X922176Y495259I2J3503D01*
G03X922014I-81J-183D01*
G02X920595Y494958I-1421J3202D01*
G02X919176Y495259I2J3503D01*
G03X919014I-81J-183D01*
G02X917595Y494958I-1421J3202D01*
G02X916287Y495212I2J3503D01*
G03X916137I-75J-186D01*
G02X914829Y494958I-1310J3249D01*
G02X913410Y495259I2J3503D01*
G03X913248I-81J-183D01*
G02X911829Y494958I-1421J3202D01*
G02X908326Y498461I0J3503D01*
G02X908548Y499686I3503J-2D01*
G03X908545Y499833I-188J70D01*
G02X908274Y501184I3232J1351D01*
G02X908574Y502603I3502J1D01*
G03Y502765I-183J81D01*
G02X908274Y504184I3202J1418D01*
G02X908574Y505603I3502J1D01*
G03Y505765I-183J81D01*
G02X908274Y507184I3202J1418D01*
G02X908574Y508603I3502J1D01*
G03Y508765I-183J81D01*
G02X908274Y510184I3202J1418D01*
G02X908574Y511603I3502J1D01*
G03Y511765I-183J81D01*
G02X908274Y513184I3202J1418D01*
G02X908574Y514603I3502J1D01*
G03Y514765I-183J81D01*
G02X908274Y516184I3202J1418D01*
G02X908566Y517584I3502J0D01*
G03X908569Y517737I-184J80D01*
G02X908328Y519014I3261J1277D01*
G02X911830Y522516I3502J0D01*
G02X913249Y522216I1J-3502D01*
G03X913411I81J183D01*
G02X914830Y522516I1418J-3202D01*
G02X916138Y522263I1J-3502D01*
G03X916288I75J186D01*
G37*
G36*
G01X839232Y519045D02*
G02X838932Y520464I3202J1418D01*
G02X839232Y521883I3502J1D01*
G03Y522045I-183J81D01*
G02X838932Y523464I3202J1418D01*
G02X842434Y526966I3502J0D01*
G02X843834Y526675I2J-3502D01*
G03X843987Y526672I80J183D01*
G02X845263Y526912I1274J-3262D01*
G02X846682Y526612I1J-3502D01*
G03X846844I81J183D01*
G02X848263Y526912I1418J-3202D01*
G02X849596Y526649I1J-3502D01*
G03X849749I77J185D01*
G02X851082Y526912I1332J-3239D01*
G02X852501Y526612I1J-3502D01*
G03X852663I81J183D01*
G02X854082Y526912I1418J-3202D01*
G02X857584Y523410I0J-3502D01*
G02X857284Y521991I-3502J-1D01*
G03Y521829I183J-81D01*
G02X857584Y520410I-3202J-1418D01*
G02X857284Y518991I-3502J-1D01*
G03Y518829I183J-81D01*
G02X857584Y517410I-3202J-1418D01*
G02X857284Y515991I-3502J-1D01*
G03Y515829I183J-81D01*
G02X857584Y514410I-3202J-1418D01*
G02X857284Y512991I-3502J-1D01*
G03Y512829I183J-81D01*
G02X857584Y511410I-3202J-1418D01*
G02X857284Y509991I-3502J-1D01*
G03Y509829I183J-81D01*
G02X857584Y508410I-3202J-1418D01*
G02X857284Y506991I-3502J-1D01*
G03Y506829I183J-81D01*
G02X857584Y505410I-3202J-1418D01*
G02X857284Y503991I-3502J-1D01*
G03Y503829I183J-81D01*
G02X857584Y502410I-3202J-1418D01*
G02X854082Y498908I-3502J0D01*
G02X852663Y499208I-1J3502D01*
G03X852501I-81J-183D01*
G02X851082Y498908I-1418J3202D01*
G02X849749Y499171I-1J3502D01*
G03X849596I-76J-185D01*
G02X848263Y498908I-1332J3239D01*
G02X846844Y499208I-1J3502D01*
G03X846682I-81J-183D01*
G02X845263Y498908I-1418J3202D01*
G02X843863Y499199I-2J3502D01*
G03X843710Y499202I-80J-183D01*
G02X842434Y498962I-1274J3262D01*
G02X838932Y502464I0J3502D01*
G02X839232Y503883I3502J1D01*
G03Y504045I-183J81D01*
G02X838932Y505464I3202J1418D01*
G02X839232Y506883I3502J1D01*
G03Y507045I-183J81D01*
G02X838932Y508464I3202J1418D01*
G02X839232Y509883I3502J1D01*
G03Y510045I-183J81D01*
G02X838932Y511464I3202J1418D01*
G02X839232Y512883I3502J1D01*
G03Y513045I-183J81D01*
G02X838932Y514464I3202J1418D01*
G02X839232Y515883I3502J1D01*
G03Y516045I-183J81D01*
G02X838932Y517464I3202J1418D01*
G02X839232Y518883I3502J1D01*
G03Y519045I-183J81D01*
G37*
G36*
G01X1063298Y548581D02*
G02X1062998Y550000I3202J1418D01*
G02X1063298Y551419I3502J1D01*
G03Y551581I-183J81D01*
G02X1062998Y553000I3202J1418D01*
G02X1066500Y556502I3502J0D01*
G02X1067919Y556202I1J-3502D01*
G03X1068081I81J183D01*
G02X1069500Y556502I1418J-3202D01*
G02X1073002Y553000I0J-3502D01*
G02X1072702Y551581I-3502J-1D01*
G03Y551419I183J-81D01*
G02X1073002Y550000I-3202J-1418D01*
G02X1072702Y548581I-3502J-1D01*
G03Y548419I183J-81D01*
G02X1073002Y547000I-3202J-1418D01*
G02X1072702Y545581I-3502J-1D01*
G03Y545419I183J-81D01*
G02X1073002Y544000I-3202J-1418D01*
G02X1072702Y542581I-3502J-1D01*
G03Y542419I183J-81D01*
G02X1073002Y541000I-3202J-1418D01*
G02X1072702Y539581I-3502J-1D01*
G03Y539419I183J-81D01*
G02X1073002Y538000I-3202J-1418D01*
G02X1069500Y534498I-3502J0D01*
G02X1068081Y534798I-1J3502D01*
G03X1067919I-81J-183D01*
G02X1066500Y534498I-1418J3202D01*
G02X1062998Y538000I0J3502D01*
G02X1063298Y539419I3502J1D01*
G03Y539581I-183J81D01*
G02X1062998Y541000I3202J1418D01*
G02X1063298Y542419I3502J1D01*
G03Y542581I-183J81D01*
G02X1062998Y544000I3202J1418D01*
G02X1063298Y545419I3502J1D01*
G03Y545581I-183J81D01*
G02X1062998Y547000I3202J1418D01*
G02X1063298Y548419I3502J1D01*
G03Y548581I-183J81D01*
G37*
G36*
G01X159774Y229052D02*
G02X159348Y230728I3076J1674D01*
G02X162850Y234230I3502J0D01*
G02X164032Y234025I1J-3502D01*
G03X164168I68J188D01*
G02X165350Y234230I1181J-3297D01*
G02X168852Y230728I0J-3502D01*
G02X168426Y229052I-3502J-2D01*
G03Y228861I175J-95D01*
G02X168852Y227185I-3076J-1674D01*
G02X168426Y225509I-3502J-2D01*
G03Y225318I175J-95D01*
G02X168852Y223642I-3076J-1674D01*
G02X168425Y221966I-3503J0D01*
G03Y221774I176J-96D01*
G02X168852Y220098I-3076J-1676D01*
G02X166105Y216678I-3502J0D01*
G03X166073Y216297I43J-195D01*
G02X166132Y216273I-1290J-3256D01*
G03X166288I78J184D01*
G02X167660Y216552I1370J-3223D01*
G02X171162Y213050I0J-3502D01*
G02X170819Y211536I-3503J-2D01*
G03Y211364I180J-86D01*
G02X171162Y209850I-3160J-1512D01*
G02X167660Y206348I-3502J0D01*
G02X166288Y206627I-2J3502D01*
G03X166132I-78J-184D01*
G02X164760Y206348I-1370J3223D01*
G02X161258Y209850I0J3502D01*
G02X161601Y211364I3503J2D01*
G03Y211536I-180J86D01*
G02X161258Y213050I3160J1512D01*
G02X162709Y215889I3503J0D01*
G01X162761Y215926D01*
X162802Y216043D01*
X162671Y216526D01*
X162576Y216606D01*
X162513Y216612D01*
G02X159348Y220098I337J3486D01*
G02X159775Y221774I3503J0D01*
G03Y221966I-176J96D01*
G02X159348Y223642I3076J1676D01*
G02X159774Y225318I3502J2D01*
G03Y225509I-175J96D01*
G02X159348Y227185I3076J1674D01*
G02X159774Y228861I3502J2D01*
G03Y229052I-175J95D01*
G37*
G36*
G01X1099239Y524880D02*
G02X1100653Y525466I1414J-1413D01*
G01X1175329D01*
G02X1176743Y524880I0J-1999D01*
G01X1181585Y520038D01*
G02X1182171Y518624I-1413J-1414D01*
G01Y497840D01*
G03X1182230Y497698I200J0D01*
G01X1196769Y483159D01*
G03X1196911Y483100I142J141D01*
G01X1258400D01*
G02X1259814Y482514I0J-1999D01*
G01X1264914Y477414D01*
G02X1265500Y476000I-1413J-1414D01*
G01Y302600D01*
G02X1264914Y301186I-1999J0D01*
G01X1260814Y297086D01*
G02X1259400Y296500I-1414J1413D01*
G01X1216111D01*
G03X1215969Y296441I0J-200D01*
G01X1208559Y289031D01*
G03X1208500Y288889I141J-142D01*
G01Y219138D01*
G02X1207914Y217724I-1999J0D01*
G01X1190372Y200182D01*
G02X1188958Y199596I-1414J1413D01*
G01X1170746D01*
G03X1170574Y199499I0J-200D01*
G01X1170371Y199159D01*
X1170368Y199055D01*
X1170393Y199008D01*
G02X1170452Y198772I-441J-236D01*
G01Y187837D01*
G02X1170253Y187438I-500J0D01*
G01X1170219Y187412D01*
X1170178Y187339D01*
X1170142Y186961D01*
X1170169Y186881D01*
X1170197Y186850D01*
G02X1171102Y184500I-2597J-2349D01*
G02X1170548Y182608I-3502J-2D01*
G03Y182392I168J-108D01*
G02X1171102Y180500I-2948J-1890D01*
G02X1167600Y176998I-3502J0D01*
G02X1166632Y177134I-2J3502D01*
G01X1166581Y177148D01*
X1166480Y177124D01*
X1166151Y176820D01*
X1166119Y176720D01*
X1166130Y176668D01*
G02X1166202Y175959I-3430J-707D01*
G02X1162700Y172456I-3502J-1D01*
G02X1161487Y172673I1J3503D01*
G03X1161352Y172674I-69J-188D01*
G02X1160200Y172480I-1149J3308D01*
G02X1156715Y175628I0J3503D01*
G03X1156597Y175791I-199J-20D01*
G02X1154498Y179000I1403J3209D01*
G02X1158000Y182502I3502J0D01*
G02X1161435Y179684I0J-3503D01*
G01X1161443Y179645D01*
X1161488Y179578D01*
X1161797Y179378D01*
X1161877Y179364D01*
X1161917Y179373D01*
G02X1162700Y179462I785J-3414D01*
G02X1163668Y179325I-2J-3503D01*
G01X1163719Y179311D01*
X1163820Y179335D01*
X1164149Y179639D01*
X1164181Y179739D01*
X1164170Y179791D01*
G02X1164098Y180500I3430J707D01*
G02X1164652Y182392I3502J2D01*
G03Y182608I-168J108D01*
G02X1164098Y184500I2948J1890D01*
G02X1164976Y186820I3502J1D01*
G01X1165005Y186853D01*
X1165030Y186935D01*
X1164979Y187322D01*
X1164933Y187395D01*
X1164896Y187419D01*
G02X1164671Y187837I276J418D01*
G01Y198772D01*
G02X1164730Y199008I500J0D01*
G01X1164755Y199055D01*
X1164752Y199159D01*
X1164549Y199499D01*
G03X1164377Y199596I-172J-103D01*
G01X1144507D01*
G03X1144365Y199537I0J-200D01*
G01X1136214Y191386D01*
G02X1134800Y190800I-1414J1413D01*
G01X1107700D01*
G02X1106286Y191386I0J1999D01*
G01X1093861Y203811D01*
G02X1093275Y205225I1413J1414D01*
G01Y518088D01*
G02X1093861Y519502I1999J0D01*
G01X1099239Y524880D01*
G37*
G54D56*
X247441Y305975D03*
X404921D03*
X562402D03*
X719883D03*
X849000Y399000D03*
X1016614Y197767D03*
X1024340Y146600D03*
X1092000Y82500D03*
X1084325Y130197D03*
X154840Y244730D03*
X1067866Y507629D03*
X1060984Y418742D03*
X1067730Y460352D03*
X1061600Y466242D03*
Y513742D03*
X1067531Y412942D03*
X1080418Y373600D03*
X1067679Y317942D03*
X1061600Y323742D03*
X1086500Y356000D03*
X1158200Y137700D03*
X1067707Y365442D03*
X1061600Y276242D03*
X1086500Y403500D03*
X1152500Y186500D03*
X1067701Y270442D03*
X1152781Y165719D03*
G54D59*
X1226024Y286929D03*
G54D60*
X48780Y329724D03*
G54D57*
X268000Y240000D03*
X312500D03*
X357000D03*
X428500D03*
X472500D03*
X516500D03*
X578500D03*
X622500D03*
X666500D03*
X735981D03*
X779981D03*
X823981D03*
G54D55*
X165539Y539000D03*
X213539D03*
X261539D03*
X323019D03*
X371019D03*
X419019D03*
X480500D03*
X528500D03*
X576500D03*
X637981D03*
X685981D03*
X733981D03*
G54D58*
X253819Y477204D03*
X411299D03*
X568780D03*
X726261D03*
G54D52*
X19922Y367716D03*
Y214173D03*
G54D53*
X964460Y16950D03*
X877510Y558620D03*
X175000Y100500D03*
X1271654Y636929D03*
X619685D03*
G54D54*
X108858Y99724D03*
Y482205D03*
G54D51*
X665059Y149408D03*
X980059D03*
X529252Y129685D03*
X249252D03*
X1226024Y174429D03*
%LPC*%
G75*
G36*
G01X1102061Y377400D02*
X1173385D01*
G02X1173527Y377341I0J-200D01*
G01X1178112Y372756D01*
G02X1178171Y372614I-141J-142D01*
G01Y338657D01*
G02X1178140Y338551I-200J1D01*
G03X1177909Y337750I1271J-800D01*
G03X1178140Y336949I1502J-1D01*
G02X1178171Y336843I-169J-107D01*
G01Y335157D01*
G02X1178140Y335051I-200J1D01*
G03X1177909Y334250I1271J-800D01*
G03X1178140Y333449I1502J-1D01*
G02X1178171Y333343I-169J-107D01*
G01Y331657D01*
G02X1178140Y331551I-200J1D01*
G03X1177909Y330750I1271J-800D01*
G03X1178140Y329949I1502J-1D01*
G02X1178171Y329843I-169J-107D01*
G01Y328157D01*
G02X1178140Y328051I-200J1D01*
G03X1177909Y327250I1271J-800D01*
G03X1178140Y326449I1502J-1D01*
G02X1178171Y326343I-169J-107D01*
G01Y310199D01*
X1178168Y310183D01*
G03X1178149Y309942I1483J-238D01*
G03X1178168Y309701I1502J-3D01*
G01X1178171Y309685D01*
Y306199D01*
X1178168Y306183D01*
G03X1178149Y305942I1483J-238D01*
G03X1178168Y305701I1502J-3D01*
G01X1178171Y305685D01*
Y293295D01*
X1178166Y293272D01*
G03X1178111Y292808I1945J-466D01*
G03X1178166Y292344I2000J2D01*
G01X1178171Y292321D01*
Y286769D01*
X1178166Y286746D01*
G03X1178111Y286282I1945J-466D01*
G03X1178166Y285818I2000J2D01*
G01X1178171Y285795D01*
Y240893D01*
G02X1178112Y240751I-200J0D01*
G01X1174527Y237166D01*
G02X1174385Y237107I-142J141D01*
G01X1101890D01*
G02X1101748Y237166I0J200D01*
G01X1097334Y241580D01*
G02X1097275Y241722I141J142D01*
G01Y372614D01*
G02X1097334Y372756I200J0D01*
G01X1101919Y377341D01*
G02X1102061Y377400I142J-141D01*
G37*
G36*
G01X1101564Y521466D02*
X1174418D01*
G02X1174560Y521407I0J-200D01*
G01X1178112Y517855D01*
G02X1178171Y517713I-141J-142D01*
G01Y480974D01*
X1178161Y480931D01*
X1178151Y480910D01*
G03X1177998Y480250I1349J-660D01*
G03X1178151Y479590I1502J0D01*
G01X1178161Y479569D01*
X1178171Y479526D01*
Y477474D01*
X1178161Y477431D01*
X1178151Y477410D01*
G03X1177998Y476750I1349J-660D01*
G03X1178151Y476090I1502J0D01*
G01X1178161Y476069D01*
X1178171Y476026D01*
Y473974D01*
X1178161Y473931D01*
X1178151Y473910D01*
G03X1177998Y473250I1349J-660D01*
G03X1178151Y472590I1502J0D01*
G01X1178161Y472569D01*
X1178171Y472526D01*
Y470474D01*
X1178161Y470431D01*
X1178151Y470410D01*
G03X1177998Y469750I1349J-660D01*
G03X1178151Y469090I1502J0D01*
G01X1178161Y469069D01*
X1178171Y469026D01*
Y386186D01*
G02X1178112Y386044I-200J0D01*
G01X1173527Y381459D01*
G02X1173385Y381400I-142J141D01*
G01X1102061D01*
G02X1101919Y381459I0J200D01*
G01X1097334Y386044D01*
G02X1097275Y386186I141J142D01*
G01Y517177D01*
G02X1097334Y517319I200J0D01*
G01X1101422Y521407D01*
G02X1101564Y521466I142J-141D01*
G37*
G36*
G01X1184104Y291643D02*
X1182230Y293517D01*
G02X1182171Y293659I141J142D01*
G01Y348245D01*
G02X1182208Y348361I200J0D01*
G03Y350107I-1222J873D01*
G02X1182171Y350223I163J116D01*
G01Y474987D01*
G02X1182230Y475129I200J0D01*
G01X1186142Y479041D01*
G02X1186284Y479100I142J-141D01*
G01X1257489D01*
G02X1257631Y479041I0J-200D01*
G01X1261441Y475231D01*
G02X1261500Y475089I-141J-142D01*
G01Y303511D01*
G02X1261441Y303369I-200J0D01*
G01X1258631Y300559D01*
G02X1258489Y300500I-142J141D01*
G01X1215200D01*
G03X1213786Y299914I0J-1999D01*
G01X1205456Y291584D01*
G02X1205314Y291525I-142J141D01*
G01X1186366D01*
X1186358Y291527D01*
G03X1185885Y291584I-474J-1943D01*
G01X1184246D01*
G02X1184104Y291643I0J200D01*
G37*
%LPD*%
G75*
G54D61*
X1226024Y399429D03*
G54D20*
X63436Y353962D03*
X108600Y258560D03*
X111600D03*
X108600Y261560D03*
X111600D03*
X108600Y255560D03*
X111600D03*
X123000Y414500D03*
X119500D03*
Y411500D03*
X123000D03*
X119500Y408500D03*
X123000D03*
X119500Y417500D03*
X123000D03*
X119500Y420500D03*
X123000D03*
X115700Y420600D03*
Y417600D03*
Y408600D03*
Y411600D03*
Y414600D03*
X123000Y426600D03*
X119500D03*
X123000Y423600D03*
X119500D03*
X115700Y423700D03*
Y426700D03*
X150634Y219063D03*
X154840Y244730D03*
X155034Y228063D03*
Y224563D03*
X152334Y223063D03*
Y226563D03*
Y230063D03*
X155034Y231563D03*
X182260Y197050D03*
X179460D03*
X176560D03*
X174660Y205850D03*
Y202650D03*
X167660Y213050D03*
X164760D03*
X167660Y209850D03*
X164760D03*
X183900Y216830D03*
X178265Y213443D03*
X175976Y218775D03*
X165840Y247805D03*
X169840D03*
X166068Y238749D03*
X173869Y228168D03*
X175481Y225183D03*
X160017Y237764D03*
X161400Y323200D03*
X157000Y414500D03*
X160500D03*
Y417500D03*
X157000D03*
X160500Y420500D03*
X157000D03*
X160500Y411500D03*
X157000D03*
X160500Y408500D03*
X157000D03*
X164000Y414600D03*
Y417600D03*
Y420600D03*
Y411600D03*
Y408600D03*
X160300Y423600D03*
X156800D03*
X160300Y426600D03*
X156800D03*
X163800Y426700D03*
Y423700D03*
X168939Y498000D03*
X171939D03*
Y518000D03*
X168939D03*
X194160Y205200D03*
Y208200D03*
X200160Y205200D03*
Y208200D03*
X197160Y205200D03*
Y208200D03*
X185260Y205350D03*
Y208350D03*
X203575Y297500D03*
X212925Y315500D03*
X218500Y309500D03*
X226975D03*
X235975D03*
X230425Y313605D03*
X221425Y313000D03*
X216939Y498000D03*
X219939D03*
Y518000D03*
X216939D03*
X247441Y305975D03*
X264939Y498000D03*
X267939D03*
Y518000D03*
X264939D03*
X283000Y203500D03*
Y198500D03*
Y196000D03*
Y206000D03*
X285219Y279078D03*
X281219D03*
X277219D03*
X285219Y275078D03*
X281219D03*
X277219D03*
X285219Y271078D03*
X281219D03*
X277219D03*
Y283078D03*
X281219D03*
X285219D03*
X326000Y203500D03*
Y198500D03*
Y196000D03*
Y206000D03*
X304500Y203500D03*
Y198500D03*
Y196000D03*
Y206000D03*
X326419Y498000D03*
X329419D03*
Y518000D03*
X326419D03*
X347500Y203500D03*
Y198500D03*
Y196000D03*
Y206000D03*
X361000Y305975D03*
X390500Y203500D03*
Y198500D03*
Y196000D03*
Y206000D03*
X369000Y203500D03*
Y198500D03*
Y196000D03*
Y206000D03*
X375500Y309500D03*
X383975D03*
X382963Y316400D03*
Y313750D03*
X374419Y498000D03*
X377419D03*
Y518000D03*
X374419D03*
X412000Y203500D03*
Y198500D03*
Y196000D03*
Y206000D03*
X404921Y305975D03*
X392975Y309500D03*
X442499Y279186D03*
X438499D03*
X434499D03*
X442499Y275186D03*
X438499D03*
X434499D03*
X442499Y271186D03*
X438499D03*
X434499D03*
Y283186D03*
X438499D03*
X442499D03*
X422419Y498000D03*
X425419D03*
Y518000D03*
X422419D03*
X483900Y498000D03*
X486900D03*
Y518000D03*
X483900D03*
X518575Y295500D03*
X533475Y310500D03*
X539619Y316400D03*
Y313400D03*
X531900Y498000D03*
X534900D03*
Y518000D03*
X531900D03*
X562402Y305975D03*
X542475Y310500D03*
X551475D03*
X562000Y442000D03*
X564500D03*
X590500Y203000D03*
Y198000D03*
Y195500D03*
Y205500D03*
X582900Y518000D03*
Y498000D03*
X579900D03*
Y518000D03*
X612000Y203000D03*
Y198000D03*
Y195500D03*
Y205500D03*
X640900Y42300D03*
X647999Y33000D03*
X638200Y44000D03*
Y46500D03*
X641100Y48100D03*
X655000Y203000D03*
Y198000D03*
Y195500D03*
Y205500D03*
X633500Y203000D03*
Y198000D03*
Y195500D03*
Y205500D03*
X644381Y518000D03*
Y498000D03*
X641381D03*
Y518000D03*
X690075Y39500D03*
X676500Y195500D03*
Y198000D03*
Y203000D03*
Y205500D03*
X676075Y299600D03*
X680400Y310500D03*
X703740Y41000D03*
X707000Y32000D03*
X694425Y29500D03*
X703740Y54118D03*
X697990Y195500D03*
Y198000D03*
Y203000D03*
Y205500D03*
X716100Y255987D03*
X700040Y258960D03*
X694406Y295500D03*
X690956Y310500D03*
X699956D03*
X708956D03*
X697100Y313400D03*
X704400Y358600D03*
X702200Y356000D03*
X697900Y352500D03*
X707750Y358750D03*
X692381Y518000D03*
Y498000D03*
X689381D03*
Y518000D03*
X747160Y30000D03*
Y38500D03*
Y64000D03*
Y47000D03*
Y55500D03*
X719490Y195500D03*
Y198000D03*
Y203000D03*
Y205500D03*
X719883Y305975D03*
X724000Y294500D03*
X742500Y328500D03*
Y324500D03*
Y334500D03*
X735075Y326000D03*
Y336000D03*
X731925D03*
X732000Y326000D03*
X742000Y341500D03*
X742500Y347700D03*
Y353200D03*
X740381Y518000D03*
Y498000D03*
X737381D03*
Y518000D03*
X750300Y27200D03*
X752560Y30100D03*
X749760D03*
X752560Y38600D03*
X749760D03*
X752560Y64100D03*
X749760D03*
X752560Y47100D03*
X749760D03*
X752560Y55600D03*
X749760D03*
X754000Y353500D03*
Y356957D03*
X748075Y366500D03*
X803900Y279425D03*
X803500Y259525D03*
X784855Y265184D03*
X790000Y259612D03*
X794900Y265979D03*
X806000Y265075D03*
X806500Y285500D03*
X800575Y338000D03*
X779100Y326820D03*
X798400Y323900D03*
X786500Y316700D03*
X793800Y323880D03*
X781500Y362700D03*
X803000Y357000D03*
Y346500D03*
X802975Y362000D03*
X792000Y358000D03*
X805323Y408150D03*
Y405150D03*
X799323D03*
Y408150D03*
X802323Y405150D03*
Y408150D03*
X796600Y408097D03*
Y405097D03*
X802323Y416916D03*
X799323D03*
X805323D03*
X802323Y413916D03*
X799323D03*
X805323D03*
Y411150D03*
X799323D03*
X802323D03*
X796600Y411097D03*
Y413863D03*
Y416863D03*
X799655Y474684D03*
Y480503D03*
Y477684D03*
X802655Y474684D03*
Y480503D03*
Y477684D03*
X805655Y474684D03*
Y480503D03*
Y477684D03*
X802655Y483503D03*
X805709Y486332D03*
X805655Y483503D03*
X796655Y474684D03*
Y480503D03*
Y477684D03*
X796709Y486332D03*
X796655Y483503D03*
X799709Y486332D03*
X799655Y483503D03*
X802709Y486332D03*
X831000Y270500D03*
X808500Y276075D03*
X836000Y270500D03*
X826000Y270525D03*
X833500Y268575D03*
X821000Y270525D03*
X816000D03*
X827602Y283500D03*
X836500Y302500D03*
X814500Y293000D03*
X811500Y329000D03*
X815500D03*
X823500D03*
X819500Y318500D03*
X808425Y334000D03*
X831750Y318250D03*
X829500Y354925D03*
X827000Y360475D03*
X811575Y344000D03*
X827000Y352500D03*
X808425Y344000D03*
X811323Y405150D03*
Y408150D03*
X808323D03*
Y405150D03*
Y416916D03*
X811323D03*
X808323Y413916D03*
X811323D03*
Y411150D03*
X808323D03*
X817153Y408096D03*
Y405096D03*
X814323Y405150D03*
Y408150D03*
Y416916D03*
X817153Y416862D03*
X814323Y413916D03*
X817153Y413862D03*
Y411096D03*
X814323Y411150D03*
X817709Y486332D03*
X817655Y483503D03*
X808655Y474684D03*
Y480503D03*
Y477684D03*
X811655Y474684D03*
Y480503D03*
Y477684D03*
X814655D03*
Y480503D03*
Y474684D03*
X808709Y486332D03*
X808655Y483503D03*
X811709Y486332D03*
X811655Y483503D03*
X814655D03*
X814709Y486332D03*
X817655Y474684D03*
Y480503D03*
Y477684D03*
X863600Y208900D03*
X841000Y270500D03*
X846000Y270525D03*
X851000D03*
X856000D03*
X843500Y268575D03*
X853500D03*
X850750Y250750D03*
X853000Y303500D03*
X861600Y304600D03*
X845000Y303000D03*
X848500Y335800D03*
X839692Y329592D03*
X854825Y330925D03*
X850500Y356925D03*
X843843Y354342D03*
X864500Y358500D03*
X849000Y399000D03*
X850390Y385878D03*
X847390D03*
X859253D03*
X856253D03*
X865542Y385771D03*
X859342Y413916D03*
X856342D03*
X865342D03*
X862342D03*
Y411150D03*
X865342D03*
X856342D03*
X859342D03*
X853619Y411097D03*
Y413863D03*
Y416863D03*
X862342Y408150D03*
Y405150D03*
X865342Y408150D03*
Y405150D03*
X856342D03*
Y408150D03*
X859342Y405150D03*
Y408150D03*
X853619Y408097D03*
Y405097D03*
X859342Y416916D03*
X856342D03*
X865342D03*
X862342D03*
X856257Y474684D03*
Y480503D03*
Y477684D03*
X859257Y474684D03*
Y480503D03*
Y477684D03*
X862257Y474684D03*
Y480503D03*
Y477684D03*
X859257Y483503D03*
X862311Y486332D03*
X862257Y483503D03*
X853257Y474684D03*
Y480503D03*
Y477684D03*
X853311Y486332D03*
X853257Y483503D03*
X856311Y486332D03*
X856257Y483503D03*
X859311Y486332D03*
X865311D03*
X865257Y483503D03*
Y474684D03*
Y480503D03*
Y477684D03*
X854082Y505410D03*
X848263D03*
X851082D03*
X854082Y508410D03*
X848263D03*
X851082D03*
X854082Y511410D03*
X848263D03*
X851082D03*
X854082Y514410D03*
X848263D03*
X851082D03*
X845263Y508410D03*
X842434Y511464D03*
X845263Y511410D03*
X842434Y514464D03*
X845263Y514410D03*
X854082Y502410D03*
X848263D03*
X851082D03*
X842434Y502464D03*
X845263Y502410D03*
X842434Y505464D03*
X845263Y505410D03*
X842434Y508464D03*
Y523464D03*
X845263Y523410D03*
X854082Y517410D03*
X848263D03*
X851082D03*
Y520410D03*
X848263D03*
X854082D03*
X842434Y517464D03*
X845263Y517410D03*
Y520410D03*
X842434Y520464D03*
X854082Y523410D03*
X848263D03*
X851082D03*
X868000Y271500D03*
X867000Y291260D03*
X870000Y304525D03*
X875000D03*
X880000D03*
X888000Y283475D03*
X870000Y312788D03*
X880000Y312855D03*
X875000Y347273D03*
X874000Y358475D03*
X885500Y352925D03*
X869000Y360500D03*
X893091Y385771D03*
X874405D03*
X877405D03*
X868542D03*
X884228D03*
X887228D03*
X868342Y416916D03*
X871342D03*
X868342Y413916D03*
X871342D03*
Y411150D03*
X868342D03*
X874172Y408096D03*
Y405096D03*
Y416862D03*
Y413862D03*
Y411096D03*
X871342Y405150D03*
Y408150D03*
X868342Y405150D03*
Y408150D03*
X868311Y486332D03*
X868257Y483503D03*
Y477684D03*
Y480503D03*
Y474684D03*
X871311Y486332D03*
X874311D03*
X874257Y477684D03*
Y480503D03*
Y474684D03*
X871257Y483503D03*
Y474684D03*
Y480503D03*
Y477684D03*
X874257Y483503D03*
X909000Y283475D03*
X904500Y292000D03*
X915000Y322425D03*
X912000Y332425D03*
X905941Y320366D03*
X903500Y327975D03*
X916260Y355000D03*
X910992Y361075D03*
X920000Y355525D03*
X923740Y345500D03*
X896091Y385771D03*
X912525Y385877D03*
X906662D03*
X903662D03*
X922454Y385771D03*
X915525Y385877D03*
X911776Y507184D03*
Y510184D03*
Y501184D03*
Y504184D03*
X923595Y498461D03*
X920595D03*
X920542Y504184D03*
X923542D03*
X920542Y501184D03*
X923542D03*
Y510184D03*
X920542D03*
X923542Y507184D03*
X920542D03*
Y513184D03*
X923542D03*
X911829Y498461D03*
X914829D03*
X917595D03*
X917542Y504184D03*
Y501184D03*
Y510184D03*
Y507184D03*
Y513184D03*
X914776D03*
Y507184D03*
Y510184D03*
Y501184D03*
Y504184D03*
X911776Y513184D03*
X920542Y516184D03*
X923542D03*
X917542D03*
X914776D03*
X911776D03*
X917596Y519014D03*
X914830D03*
X911830D03*
X923596D03*
X920596D03*
X940575Y304000D03*
X926000Y283475D03*
X937516Y300075D03*
X947000Y302475D03*
X940000Y283800D03*
X930500Y315460D03*
X943172Y310885D03*
X943171Y315385D03*
X935516Y361075D03*
X927000Y357925D03*
X943885Y352385D03*
X933357Y344843D03*
X933196Y353360D03*
X925454Y385771D03*
X944247Y385877D03*
X941247D03*
X931317Y385771D03*
X934317D03*
X950110Y385877D03*
X953110D03*
X1022575Y100925D03*
Y115500D03*
X1034500Y145000D03*
X1037000Y146300D03*
X1037500Y142000D03*
X1036500Y153500D03*
X1043936Y145745D03*
X1019040Y157310D03*
X1019030Y160330D03*
X1022168Y155877D03*
Y161783D03*
X1017909Y151424D03*
X1017837Y154280D03*
X1024340Y146600D03*
X1016614Y187267D03*
Y190267D03*
X1036500Y172000D03*
Y163000D03*
X1039016Y189075D03*
Y183027D03*
X1039538Y179208D03*
X1039016Y185925D03*
X1022000Y171200D03*
X1019700Y166600D03*
X1016614Y197767D03*
X1057525Y130500D03*
X1049356Y143900D03*
X1047159Y141487D03*
X1054500Y148500D03*
X1048000Y153500D03*
X1057525Y134000D03*
Y138600D03*
X1073154Y140800D03*
X1057500Y155877D03*
X1070715Y146500D03*
X1063500Y159814D03*
X1048000Y172000D03*
Y163000D03*
X1060500Y164500D03*
X1062500Y191500D03*
X1067000D03*
X1070000D03*
X1058000D03*
X1053830Y191670D03*
X1060000Y249000D03*
X1063000D03*
X1066000D03*
Y246000D03*
X1063000D03*
X1060000D03*
X1066000Y243000D03*
X1063000D03*
X1060000D03*
X1069000Y246000D03*
Y243000D03*
X1072000Y246000D03*
Y243000D03*
X1060000Y252000D03*
X1063000D03*
X1066000D03*
Y258000D03*
X1063000D03*
X1060000D03*
X1066000Y255000D03*
X1063000D03*
X1060000D03*
X1069000Y258000D03*
Y255000D03*
X1072000Y258000D03*
Y255000D03*
X1067701Y270442D03*
X1061600Y276242D03*
X1060000Y296500D03*
X1063000D03*
X1066000D03*
Y293500D03*
X1063000D03*
X1060000D03*
X1069000D03*
X1060000Y299500D03*
X1063000D03*
X1066000D03*
Y305500D03*
X1063000D03*
X1060000D03*
X1066000Y302500D03*
X1063000D03*
X1060000D03*
X1069000Y305500D03*
Y302500D03*
X1066000Y290500D03*
X1063000D03*
X1060000D03*
X1069000D03*
X1072000Y293500D03*
Y305500D03*
Y302500D03*
Y290500D03*
X1066000Y338000D03*
X1063000D03*
X1060000D03*
X1069000D03*
X1072000D03*
X1067679Y317942D03*
X1061600Y323742D03*
X1060000Y344000D03*
X1063000D03*
X1066000D03*
X1060000Y347000D03*
X1063000D03*
X1066000D03*
Y341000D03*
X1063000D03*
X1060000D03*
X1066000Y353000D03*
X1063000D03*
X1060000D03*
X1066000Y350000D03*
X1063000D03*
X1060000D03*
X1069000Y353000D03*
Y350000D03*
Y341000D03*
X1072000Y353000D03*
Y350000D03*
Y341000D03*
X1067707Y365442D03*
X1061600Y359642D03*
X1066000Y397500D03*
X1063000D03*
X1060000D03*
X1069000D03*
X1060000Y391500D03*
X1063000D03*
X1066000D03*
X1060000Y394500D03*
X1063000D03*
X1066000D03*
Y388500D03*
X1063000D03*
X1060000D03*
X1066000Y385500D03*
X1063000D03*
X1060000D03*
X1069000Y388500D03*
Y385500D03*
X1072000Y397500D03*
Y388500D03*
Y385500D03*
X1066000Y400500D03*
X1063000D03*
X1060000D03*
X1069000D03*
X1072000D03*
X1067531Y412942D03*
X1060984Y418742D03*
X1066000Y433000D03*
X1063000D03*
X1060000D03*
X1069000D03*
X1060000Y439000D03*
X1063000D03*
X1066000D03*
X1060000Y442000D03*
X1063000D03*
X1066000D03*
Y436000D03*
X1063000D03*
X1060000D03*
X1069000D03*
X1072000Y433000D03*
Y436000D03*
X1066000Y448000D03*
X1063000D03*
X1060000D03*
X1066000Y445000D03*
X1063000D03*
X1060000D03*
X1069000Y448000D03*
Y445000D03*
X1072000Y448000D03*
Y445000D03*
X1069000Y480500D03*
Y483500D03*
X1060000Y480500D03*
X1063000D03*
X1066000D03*
X1060000Y483500D03*
X1063000D03*
X1066000D03*
Y486500D03*
X1063000D03*
X1060000D03*
X1072000Y480500D03*
Y483500D03*
X1067730Y460352D03*
X1061600Y466242D03*
X1069000Y492500D03*
Y495500D03*
X1060000Y492500D03*
X1063000D03*
X1066000D03*
X1060000Y495500D03*
X1063000D03*
X1066000D03*
Y489500D03*
X1063000D03*
X1060000D03*
X1072000Y492500D03*
Y495500D03*
X1067866Y507629D03*
X1061600Y513742D03*
X1066500Y538000D03*
Y541000D03*
X1069500D03*
X1066500Y544000D03*
X1069500D03*
Y538000D03*
Y547000D03*
Y550000D03*
X1066500Y547000D03*
Y550000D03*
Y553000D03*
X1069500D03*
X1092000Y82500D03*
X1087000Y100000D03*
X1073200Y90900D03*
X1077200D03*
X1084325Y130197D03*
X1094493Y151856D03*
X1073154Y137800D03*
X1082000Y143600D03*
X1092000Y159500D03*
X1094500Y143144D03*
X1084401Y159260D03*
X1094024Y179500D03*
X1085000Y184575D03*
X1079500D03*
X1085525Y167500D03*
Y171000D03*
Y174500D03*
Y164000D03*
X1087500Y198000D03*
Y201000D03*
X1097500Y203700D03*
X1100000D03*
X1073500Y191500D03*
X1086500Y356000D03*
X1080418Y373600D03*
X1086500Y403500D03*
X1074316Y406925D03*
X1123000Y120816D03*
X1126000D03*
X1131500D03*
X1115800Y126600D03*
X1130125Y135940D03*
X1126075Y135973D03*
X1121238Y144500D03*
X1108500Y136500D03*
X1104500Y136524D03*
X1120524Y138457D03*
X1129000Y157000D03*
X1120200D03*
X1115425Y138925D03*
X1119000Y189500D03*
X1111100Y163749D03*
X1123500Y187000D03*
X1108000Y172000D03*
X1113368Y171619D03*
X1110800Y170000D03*
X1113129Y165719D03*
X1114500Y188700D03*
X1120200Y176500D03*
Y166500D03*
X1129000D03*
Y176500D03*
X1108821Y166800D03*
X1125918Y195418D03*
X1129068Y195500D03*
X1133000Y198000D03*
X1117206Y231741D03*
X1117290Y224241D03*
X1106189D03*
X1106106Y231741D03*
X1134500Y120816D03*
X1158200Y137700D03*
X1136300Y161100D03*
X1140000D03*
X1160200Y175982D03*
X1152781Y165719D03*
X1136300Y172300D03*
X1140000D03*
X1140336Y183560D03*
X1143490D03*
X1152500Y186500D03*
X1158000Y179000D03*
X1162700Y175959D03*
X1183021Y165952D03*
X1185521D03*
X1188600Y166000D03*
X1188618Y162782D03*
X1185521Y162952D03*
X1183021D03*
X1180521D03*
Y165952D03*
X1177521D03*
Y162952D03*
X1167600Y184500D03*
Y180500D03*
X1174500Y214000D03*
Y211000D03*
Y208000D03*
Y205000D03*
X1171500D03*
Y208000D03*
Y211000D03*
Y214000D03*
X1179651Y305942D03*
Y309942D03*
X1165070Y328750D03*
X1193411D03*
X1179411Y334250D03*
Y337750D03*
Y330750D03*
Y327250D03*
X1180986Y349234D03*
X1177836D03*
X1179877Y452442D03*
Y448442D03*
X1165190Y471250D03*
X1179500Y476750D03*
Y480250D03*
Y469750D03*
Y473250D03*
X1181075Y491734D03*
X1177925D03*
X1193840Y471250D03*
G54D12*
X72836Y47244D03*
Y535433D03*
X466536Y47244D03*
X860237D03*
X943225Y228000D03*
X985225Y542500D03*
G54D35*
X268000Y240000D03*
X312500D03*
X357000D03*
X428500D03*
X472500D03*
X516500D03*
X578500D03*
X622500D03*
X666500D03*
X735981D03*
X779981D03*
X823981D03*
G54D16*
X38780Y272598D03*
Y279291D03*
Y292598D03*
Y299291D03*
X48780Y272598D03*
Y279291D03*
Y292598D03*
Y299291D03*
G54D25*
X165350Y220098D03*
X162850D03*
Y227185D03*
Y230728D03*
X165350Y223642D03*
Y227185D03*
Y230728D03*
X162850Y223642D03*
G54D28*
X165539Y539000D03*
X213539D03*
X261539D03*
X323019D03*
X371019D03*
X419019D03*
X480500D03*
X528500D03*
X576500D03*
X637981D03*
X685981D03*
X733981D03*
G54D17*
X33780Y334724D03*
Y314724D03*
X38780Y319724D03*
Y329724D03*
Y339724D03*
X33780Y344724D03*
X38780Y349724D03*
X48780Y319724D03*
Y329724D03*
Y339724D03*
X43780Y314724D03*
Y324724D03*
Y334724D03*
X48780Y349724D03*
X43780Y344724D03*
G54D23*
X155140Y240230D03*
X172934Y219110D03*
X172712Y222263D03*
X183815Y220903D03*
X808500Y272925D03*
X831000Y260500D03*
X836000D03*
X825941Y339560D03*
X835610Y355590D03*
X841000Y260525D03*
X865000Y313200D03*
X878000Y358475D03*
X883000Y358500D03*
X1070400Y123200D03*
X1067600D03*
X1111452Y544000D03*
Y541000D03*
X1114452Y544000D03*
Y541000D03*
Y538000D03*
X1111452D03*
X1120669Y544000D03*
Y541000D03*
X1123669Y544000D03*
Y541000D03*
Y538000D03*
X1120669D03*
X1114452Y553000D03*
X1111452D03*
X1114452Y550000D03*
X1111452D03*
X1114452Y547000D03*
X1111452D03*
X1123669Y553000D03*
X1120669D03*
X1123669Y550000D03*
X1120669D03*
X1123669Y547000D03*
X1120669D03*
G54D27*
X180539Y498000D03*
X183539D03*
X228539D03*
X231539D03*
X276539D03*
X279539D03*
X338019D03*
X341019D03*
X386019D03*
X389019D03*
X434019D03*
X437019D03*
X498500D03*
X495500D03*
X546500D03*
X543500D03*
X594500D03*
X591500D03*
X655981D03*
X652981D03*
X703981D03*
X700981D03*
X748981D03*
X751981D03*
X826000Y260525D03*
X848075Y306500D03*
X912500Y327975D03*
X1159710Y306037D03*
X1156710D03*
X1159710Y303037D03*
X1156710D03*
X1159710Y300037D03*
X1156710D03*
X1159710Y297037D03*
X1156710D03*
Y294037D03*
X1159710D03*
Y309037D03*
X1156710D03*
X1159710Y312037D03*
X1156710D03*
X1159710Y321037D03*
X1156710D03*
X1159710Y318037D03*
X1156710D03*
X1159710Y315037D03*
X1156710D03*
X1159799Y448537D03*
X1156799D03*
X1159799Y445537D03*
X1156799D03*
X1159799Y442537D03*
X1156799D03*
X1159799Y439537D03*
X1156799D03*
Y436537D03*
X1159799D03*
Y454537D03*
X1156799D03*
X1159799Y451537D03*
X1156799D03*
X1159799Y457537D03*
X1156799D03*
X1159799Y463537D03*
X1156799D03*
X1159799Y460537D03*
X1156799D03*
X1162710Y306037D03*
Y303037D03*
Y300037D03*
Y297037D03*
Y294037D03*
Y309037D03*
Y312037D03*
Y321037D03*
Y318037D03*
Y315037D03*
X1162799Y448537D03*
Y445537D03*
Y442537D03*
Y439537D03*
Y436537D03*
Y454537D03*
Y451537D03*
Y457537D03*
Y463537D03*
Y460537D03*
G54D30*
X208071Y267204D03*
X200197D03*
X215945D03*
X231693D03*
X223819D03*
X239567D03*
X247441D03*
X357677D03*
X365551D03*
X373425D03*
X389173D03*
X381299D03*
X404921D03*
X397047D03*
X523032D03*
X515158D03*
X530906D03*
X538780D03*
X546654D03*
X562402D03*
X554528D03*
X680513D03*
X672639D03*
X688387D03*
X704135D03*
X696261D03*
X712009D03*
X719883D03*
G54D33*
X223819Y477204D03*
X253819D03*
X381299D03*
X411299D03*
X538780D03*
X568780D03*
X696261D03*
X726261D03*
G54D38*
X411752Y129685D03*
X401752D03*
X411752Y139685D03*
Y149685D03*
Y159685D03*
X401752Y139685D03*
Y149685D03*
Y159685D03*
X446752Y129685D03*
X436752D03*
X446752Y139685D03*
Y149685D03*
Y159685D03*
X436752Y139685D03*
Y149685D03*
Y159685D03*
X481752Y129685D03*
X471752D03*
X481752Y139685D03*
Y149685D03*
Y159685D03*
X471752Y139685D03*
Y149685D03*
Y159685D03*
X712559Y129408D03*
Y119408D03*
Y149408D03*
Y139408D03*
X722559Y129408D03*
Y119408D03*
X747559Y129408D03*
Y119408D03*
X722559Y149408D03*
Y139408D03*
X747559Y149408D03*
Y139408D03*
X757559Y129408D03*
Y119408D03*
Y149408D03*
Y139408D03*
X782559Y129408D03*
Y119408D03*
X792559Y129408D03*
Y119408D03*
X782559Y149408D03*
Y139408D03*
X792559Y149408D03*
Y139408D03*
X812559Y119408D03*
Y129408D03*
X822559Y119408D03*
Y129408D03*
X832559Y119408D03*
Y129408D03*
X812559Y149408D03*
X822559Y139408D03*
Y149408D03*
X832559Y139408D03*
Y149408D03*
X1226024Y286929D03*
X1236024D03*
X1246024D03*
X1256024D03*
G54D43*
X1011000Y98000D03*
Y118000D03*
X1161000Y90400D03*
X1151000D03*
X1171000D03*
G54D40*
X766498Y602542D03*
X766604Y630687D03*
X766498Y612542D03*
X766604Y640687D03*
X1082833Y602542D03*
Y612542D03*
Y630687D03*
Y640687D03*
G54D37*
X296752Y129685D03*
Y139685D03*
Y149685D03*
Y159685D03*
X331752Y129685D03*
X306752D03*
X331752Y139685D03*
Y149685D03*
Y159685D03*
X306752Y139685D03*
Y149685D03*
Y159685D03*
X341752Y129685D03*
Y139685D03*
Y149685D03*
Y159685D03*
X376752Y129685D03*
X366752D03*
X376752Y139685D03*
Y149685D03*
Y159685D03*
X366752Y139685D03*
Y149685D03*
Y159685D03*
X1226024Y221929D03*
X1236024D03*
X1246024D03*
X1226024Y231929D03*
X1236024D03*
X1246024D03*
X1226024Y256929D03*
X1236024D03*
X1246024D03*
X1226024Y266929D03*
X1236024D03*
X1246024D03*
X1226024Y306929D03*
X1236024D03*
X1246024D03*
X1226024Y316929D03*
X1236024D03*
X1246024D03*
X1226024Y341929D03*
X1236024D03*
X1246024D03*
X1226024Y351929D03*
X1236024D03*
X1246024D03*
X1256024Y221929D03*
Y231929D03*
Y256929D03*
Y266929D03*
Y306929D03*
Y316929D03*
Y341929D03*
Y351929D03*
G54D26*
X178819Y277204D03*
X193819D03*
X336299D03*
X351299D03*
X493780D03*
X508780D03*
X651261D03*
X666261D03*
G54D44*
X1011000Y108000D03*
G54D29*
X185224Y539000D03*
X233224D03*
X281224D03*
X342704D03*
X390704D03*
X438704D03*
X500185D03*
X548185D03*
X596185D03*
X657666D03*
X705666D03*
X753666D03*
G54D46*
X1096017Y635687D03*
G54D45*
Y607542D03*
G54D36*
X253819Y277204D03*
X268819D03*
X411299D03*
X426299D03*
X568780D03*
X583780D03*
X726261D03*
X741261D03*
G54D13*
X118111Y47244D03*
Y535433D03*
X511811Y47244D03*
X905512D03*
X988500Y228000D03*
X1030500Y542500D03*
G54D11*
X19685Y-614173D03*
Y636929D03*
X619685D03*
X1271654Y-614173D03*
Y636929D03*
G54D14*
X19922Y214173D03*
Y367716D03*
G54D24*
X175000Y100500D03*
X877510Y558620D03*
X964460Y16950D03*
G54D21*
X82795Y99724D03*
Y482205D03*
G54D32*
X249252Y129685D03*
X529252D03*
X665059Y149408D03*
X980059D03*
X1226024Y174429D03*
Y399429D03*
G54D19*
X60630Y99724D03*
Y482205D03*
X108858Y99724D03*
Y482205D03*
G54D22*
X153480Y213350D03*
X941035Y344474D03*
X1097100Y35582D03*
Y38582D03*
X1099600D03*
Y35582D03*
X1102100D03*
Y38582D03*
X1096961Y18126D03*
Y21126D03*
X1099461D03*
Y18126D03*
X1101961D03*
Y21126D03*
X1097101Y53737D03*
Y56737D03*
X1099601D03*
Y53737D03*
X1102101D03*
Y56737D03*
X1125170Y35582D03*
Y38582D03*
X1127670D03*
Y35582D03*
X1130170D03*
Y38582D03*
X1104600Y35582D03*
Y38582D03*
X1107100Y35582D03*
Y38582D03*
X1104461Y18126D03*
Y21126D03*
X1106961Y18126D03*
Y21126D03*
X1130031D03*
Y18126D03*
X1127531D03*
Y21126D03*
X1125031D03*
Y18126D03*
X1104601Y53737D03*
Y56737D03*
X1107101Y53737D03*
Y56737D03*
X1132670Y35582D03*
X1135170D03*
Y38582D03*
X1132670D03*
X1135031Y21126D03*
Y18126D03*
X1132531Y21126D03*
Y18126D03*
X1132950Y82867D03*
Y85867D03*
X1135450D03*
Y82867D03*
X1137950D03*
X1140450D03*
X1142950D03*
Y85867D03*
X1140450D03*
X1137950D03*
X1183321Y123652D03*
X1185821D03*
X1188321D03*
Y120652D03*
X1185821D03*
X1183321D03*
X1180821D03*
Y123652D03*
X1178321D03*
Y120652D03*
G54D10*
X3005Y19808D03*
Y34808D03*
Y59808D03*
X7595Y128373D03*
X3005Y145238D03*
Y165238D03*
Y185238D03*
Y205238D03*
Y225238D03*
Y245238D03*
Y265238D03*
Y285238D03*
Y305238D03*
Y325238D03*
Y345238D03*
Y365238D03*
Y385238D03*
Y405238D03*
Y425238D03*
Y445238D03*
X3023Y524312D03*
Y549312D03*
X4540Y566003D03*
X34582Y3004D03*
X14811Y3732D03*
X12767Y72072D03*
X27271Y127298D03*
X19558Y454589D03*
X9913Y510026D03*
X20498Y575739D03*
X54582Y3004D03*
X39549Y454916D03*
X40498Y575739D03*
X60498D03*
X94582Y3004D03*
X74582D03*
X80498Y575739D03*
X114582Y3004D03*
X100498Y575739D03*
X120498D03*
X154582Y3004D03*
X134582D03*
X140400Y258360D03*
X143400D03*
X140400Y261360D03*
X143400D03*
X140400Y255360D03*
X143400D03*
X140498Y575739D03*
X174582Y3004D03*
X184349Y212651D03*
X173265Y340552D03*
X183539Y518000D03*
X180539D03*
X214582Y3004D03*
X194582D03*
X189760Y242100D03*
Y245100D03*
X192760Y242100D03*
Y245100D03*
X195760Y242100D03*
Y245100D03*
X198760Y242100D03*
Y245100D03*
X201760Y242100D03*
Y245100D03*
X208071Y305975D03*
X234582Y3004D03*
X246000Y238500D03*
X242500Y243000D03*
Y247500D03*
X218500Y305000D03*
X226975D03*
X235975D03*
X239567Y305975D03*
X223819Y445025D03*
X231539Y518000D03*
X228539D03*
X254582Y3004D03*
X246000Y235500D03*
X294582Y3004D03*
X274582D03*
X297000Y206000D03*
Y203500D03*
Y198500D03*
Y196000D03*
X290720Y340338D03*
X279539Y518000D03*
X276539D03*
X314582Y3004D03*
X318500Y206000D03*
Y203500D03*
Y198500D03*
Y196000D03*
X313571Y340552D03*
X354582Y3004D03*
X334582D03*
X340000Y206000D03*
Y203500D03*
Y198500D03*
Y196000D03*
X361500Y206000D03*
Y203500D03*
Y198500D03*
Y196000D03*
X341019Y518000D03*
X338019D03*
X374582Y3004D03*
X383000Y206000D03*
Y203500D03*
Y198500D03*
Y196000D03*
X375475Y305000D03*
X383975D03*
X365551Y305975D03*
X381299Y445025D03*
X389019Y518000D03*
X386019D03*
X414582Y3004D03*
X394582D03*
X404500Y206000D03*
Y203500D03*
Y198500D03*
Y196000D03*
X402000Y235000D03*
Y238000D03*
X398500Y247000D03*
Y242500D03*
X393000Y305000D03*
X397047Y305975D03*
X434582Y3004D03*
X426000Y206000D03*
Y203500D03*
Y198500D03*
Y196000D03*
X447255Y340339D03*
X430019Y444260D03*
X432019Y452025D03*
X437019Y518000D03*
X434019D03*
X474582Y3004D03*
X454582D03*
X473095Y340339D03*
X494582Y3004D03*
X498500Y518000D03*
X495500D03*
X534582Y3004D03*
X514582D03*
X533475Y305500D03*
X523032Y305975D03*
X538780Y445025D03*
X554582Y3004D03*
X555500Y239000D03*
Y236000D03*
X552000Y243500D03*
Y247000D03*
X542475Y305500D03*
X551475D03*
X554528Y305975D03*
X545063Y340339D03*
X549500Y445024D03*
X546500Y518000D03*
X543500D03*
X594582Y3004D03*
X574582D03*
X587500Y444260D03*
X589500Y446500D03*
X594500Y518000D03*
X591500D03*
X614582Y3004D03*
X604500Y205500D03*
Y203000D03*
Y198000D03*
Y195500D03*
X626000Y205500D03*
Y203000D03*
Y198000D03*
Y195500D03*
X654582Y3004D03*
X634582D03*
X647975Y37000D03*
X660200Y56800D03*
X655300D03*
X652300D03*
X647500Y205500D03*
Y203000D03*
Y198000D03*
Y195500D03*
X655981Y518000D03*
X652981D03*
X674582Y3004D03*
X684525Y32500D03*
Y36500D03*
X683600Y56800D03*
X679000D03*
X676000D03*
X686500D03*
X671100D03*
X668100D03*
X663200D03*
X669000Y205500D03*
Y203000D03*
Y198000D03*
Y195500D03*
X680513Y305975D03*
X714582Y3004D03*
X694582D03*
X699500Y34500D03*
X696900Y53300D03*
X694200D03*
X691400D03*
X689900Y56600D03*
X693000D03*
X696100Y56700D03*
X706000Y61975D03*
X690500Y205500D03*
Y203000D03*
Y198000D03*
Y195500D03*
X711990D03*
Y198000D03*
Y203000D03*
Y205500D03*
X709500Y247000D03*
X709481Y243500D03*
X712981Y236000D03*
Y239000D03*
X712009Y305975D03*
X708956Y305500D03*
X690956D03*
X700000D03*
X696261Y445024D03*
X703981Y518000D03*
X700981D03*
X734582Y3004D03*
X733490Y195500D03*
Y198000D03*
Y203000D03*
Y205500D03*
X732100Y332400D03*
X742500Y361500D03*
X774582Y3004D03*
X754582D03*
X761560Y38500D03*
X758760D03*
X756160D03*
X761560Y30000D03*
X758760D03*
X756160D03*
X758900Y27400D03*
X761560Y55500D03*
X758760D03*
X756160D03*
X761560Y47000D03*
X758760D03*
X756160D03*
X761560Y64000D03*
X758760D03*
X756160D03*
X751981Y518000D03*
X748981D03*
X794582Y3004D03*
X797854Y259539D03*
X786500Y336484D03*
X834582Y3004D03*
X814582D03*
X809500Y259430D03*
X819500Y329000D03*
X827500D03*
X813975Y362000D03*
Y357000D03*
X854582Y3004D03*
X849490Y196000D03*
Y198500D03*
Y203500D03*
Y206000D03*
X846000Y260525D03*
X851000D03*
X856000D03*
X837575Y321000D03*
X844760Y336077D03*
X850500Y360075D03*
Y366000D03*
X847500D03*
X856500D03*
X859500D03*
X865500D03*
X894582Y3004D03*
X874582D03*
X894500Y283475D03*
X884000D03*
X877500D03*
X893363Y298740D03*
X883000Y293925D03*
X877500Y366000D03*
X874500D03*
X884000D03*
X887000D03*
X893500D03*
X868500D03*
X914582Y3004D03*
X915500Y283475D03*
X914500Y292000D03*
X905000Y283475D03*
X905941Y306500D03*
X916260Y337077D03*
X908000Y327975D03*
X896500Y366000D03*
X906000D03*
X903000D03*
X912500D03*
X915500D03*
X922000D03*
X901063Y352340D03*
X934582Y3004D03*
X933000Y293476D03*
X940000D03*
X947000D03*
X933196Y309910D03*
X925000Y366000D03*
X944000D03*
X941000D03*
X934500D03*
X950500D03*
X953500D03*
X931500D03*
X927000Y361075D03*
X940498Y575739D03*
X974582Y3004D03*
X954582D03*
X960498Y575739D03*
X980498D03*
X994582Y3004D03*
X1000498Y575739D03*
X1034582Y3004D03*
X1014582D03*
X1034500Y142000D03*
X1020498Y575739D03*
X1040498D03*
X1054582Y3004D03*
X1068900Y110000D03*
X1065000Y156425D03*
X1070715Y178585D03*
X1060498Y575739D03*
X1094582Y3004D03*
X1074582D03*
X1091000Y99500D03*
X1095100D03*
X1073200Y126000D03*
Y128800D03*
Y123200D03*
X1084740Y108000D03*
X1100075Y139925D03*
X1084260Y152600D03*
X1101903Y285019D03*
X1101796Y331894D03*
X1090500Y376500D03*
X1090443Y417343D03*
X1080498Y575739D03*
X1100498D03*
X1114582Y3004D03*
X1113000Y101240D03*
X1119500Y86000D03*
Y83000D03*
X1113500Y147500D03*
X1118774Y284699D03*
X1112902D03*
X1110019Y284806D03*
X1104786Y284912D03*
X1121657Y284592D03*
X1118667Y331574D03*
X1112795D03*
X1109912Y331681D03*
X1104679Y331787D03*
X1121550Y331467D03*
X1104009Y427245D03*
X1120880Y426925D03*
X1115008D03*
X1112125Y427032D03*
X1106892Y427138D03*
X1123763Y426818D03*
X1103800Y474339D03*
X1106683Y474232D03*
X1111916Y474126D03*
X1114799Y474019D03*
X1120671D03*
X1123554Y473912D03*
X1120498Y575739D03*
X1154582Y3004D03*
X1134582D03*
X1155000Y124913D03*
X1159300Y129700D03*
X1141500Y124425D03*
Y120500D03*
X1154000Y151500D03*
X1141500Y134575D03*
X1138203Y266860D03*
Y260860D03*
Y263860D03*
X1135203Y260860D03*
Y263860D03*
Y266860D03*
X1138203Y257860D03*
Y254860D03*
X1135203Y257860D03*
Y254860D03*
X1135403Y302360D03*
Y305360D03*
X1138403Y302360D03*
Y305360D03*
X1135403Y308360D03*
X1138403D03*
X1135403Y314360D03*
Y311360D03*
X1138403D03*
Y314360D03*
Y361979D03*
X1135403D03*
X1138403Y358979D03*
X1135403D03*
X1138403Y355979D03*
X1135403D03*
X1138403Y352979D03*
X1135403D03*
X1138403Y349979D03*
X1135403D03*
X1135190Y396965D03*
X1138190D03*
X1135190Y399965D03*
X1138190D03*
X1135190Y402965D03*
Y405965D03*
Y408965D03*
X1138190Y402965D03*
Y405965D03*
Y408965D03*
X1135404Y457228D03*
Y454228D03*
Y451228D03*
Y445228D03*
Y448228D03*
X1138404Y454228D03*
Y451228D03*
Y445228D03*
Y448228D03*
Y457228D03*
X1135622Y485732D03*
Y470732D03*
Y467732D03*
Y479732D03*
Y476732D03*
Y473732D03*
Y482732D03*
X1138622D03*
Y473732D03*
Y476732D03*
Y479732D03*
Y470732D03*
Y485732D03*
Y467732D03*
X1140498Y575739D03*
X1160498D03*
X1174582Y3004D03*
X1177475Y111500D03*
X1179500Y105500D03*
X1180498Y575739D03*
X1214582Y3004D03*
X1194582D03*
X1203887Y306894D03*
X1200887D03*
X1197887D03*
X1203887Y303894D03*
X1200887D03*
X1197887D03*
X1203887Y300894D03*
X1200887D03*
X1197887D03*
X1203887Y297894D03*
X1200887D03*
X1197887D03*
X1203887Y294894D03*
X1200887D03*
X1197887D03*
Y321894D03*
X1200887D03*
X1203887D03*
Y318894D03*
X1200887D03*
X1197887D03*
X1203887Y315894D03*
X1200887D03*
X1197887D03*
X1203887Y312894D03*
X1200887D03*
X1197887D03*
X1203887Y309894D03*
X1200887D03*
X1197887D03*
X1197976Y437394D03*
X1200976D03*
X1203976D03*
X1197976Y440394D03*
X1200976D03*
X1203976D03*
X1197976Y443394D03*
X1200976D03*
X1203976D03*
X1197976Y446394D03*
X1200976D03*
X1203976D03*
X1197976Y449394D03*
X1200976D03*
X1203976D03*
X1197976Y452394D03*
X1200976D03*
X1203976D03*
X1197976Y455394D03*
X1200976D03*
X1203976D03*
X1197976Y464394D03*
X1200976D03*
X1203976D03*
X1197976Y458394D03*
X1200976D03*
X1203976D03*
X1197976Y461394D03*
X1200976D03*
X1203976D03*
X1200498Y575739D03*
X1220498D03*
X1234582Y3004D03*
X1240498Y575739D03*
X1277657Y4128D03*
X1254582Y3004D03*
X1260498Y575739D03*
X1279438Y573806D03*
X1286766Y12634D03*
X1288331Y30962D03*
Y70962D03*
Y50962D03*
Y90962D03*
Y130962D03*
Y110962D03*
Y150962D03*
Y190962D03*
Y170962D03*
Y210962D03*
Y230962D03*
Y270962D03*
Y250962D03*
Y290962D03*
Y330962D03*
Y310962D03*
Y350962D03*
Y390962D03*
Y370962D03*
Y410962D03*
Y450962D03*
Y430962D03*
Y470962D03*
Y510962D03*
Y490962D03*
Y530962D03*
X1287616Y563889D03*
X1288331Y550962D03*
G54D42*
X812559Y139408D03*
X852559Y129408D03*
Y119408D03*
X862559Y129408D03*
Y119408D03*
X852559Y149408D03*
Y139408D03*
X862559Y149408D03*
Y139408D03*
X887559Y129408D03*
Y119408D03*
Y149408D03*
Y139408D03*
X897559Y129408D03*
Y119408D03*
X922559Y129408D03*
Y119408D03*
X897559Y149408D03*
Y139408D03*
X922559Y149408D03*
Y139408D03*
X932559Y129408D03*
Y119408D03*
Y149408D03*
Y139408D03*
G54D48*
X1226024Y174429D03*
Y399429D03*
G54D18*
X33780Y324724D03*
G54D34*
X268000Y220315D03*
X312500D03*
X357000D03*
X428500D03*
X472500D03*
X516500D03*
X578500D03*
X622500D03*
X666500D03*
X735981D03*
X779981D03*
X823981D03*
G54D15*
X38780Y232598D03*
Y239291D03*
Y252598D03*
Y259291D03*
X48780Y232598D03*
Y239291D03*
Y252598D03*
Y259291D03*
G54D47*
X1240158Y57480D03*
Y521260D03*
G54D31*
X193819Y477204D03*
X351299D03*
X508780D03*
X666261D03*
G54D39*
X753314Y607542D03*
G54D41*
X753420Y635687D03*
%LPC*%
G75*
G54D50*
G01X-297025Y-1013390D02*
Y1828909D01*
X3691357D01*
Y-1013390D01*
X-297025D01*
G01X4093Y-769672D02*
Y-844672D01*
X504093D01*
Y-769672D01*
X4093D01*
G01X16093Y-834672D02*
Y-839672D01*
G01X14636Y-834672D02*
X17550D01*
G01X22460Y-839672D02*
X19926D01*
Y-834672D01*
X22460D01*
G01X21446Y-837089D02*
X19926D01*
G01X25026Y-834672D02*
Y-839672D01*
X27560D01*
G01X31393Y-839839D02*
X31266Y-839755D01*
Y-839589D01*
X31393Y-839505D01*
X31520Y-839589D01*
Y-839755D01*
X31393Y-839839D01*
G01Y-837589D02*
X31266Y-837505D01*
Y-837339D01*
X31393Y-837255D01*
X31520Y-837339D01*
Y-837505D01*
X31393Y-837589D01*
G01X36176Y-841339D02*
X35543Y-840505D01*
X35226Y-839672D01*
Y-836339D01*
X35543Y-835505D01*
X36176Y-834672D01*
G01X41593D02*
X41086Y-834839D01*
X40706Y-835255D01*
X40453Y-835755D01*
X40263Y-836422D01*
X40200Y-837172D01*
X40263Y-837922D01*
X40453Y-838589D01*
X40706Y-839089D01*
X41086Y-839505D01*
X41593Y-839672D01*
X42100Y-839505D01*
X42480Y-839089D01*
X42733Y-838589D01*
X42923Y-837922D01*
X42986Y-837172D01*
X42923Y-836422D01*
X42733Y-835755D01*
X42480Y-835255D01*
X42100Y-834839D01*
X41593Y-834672D01*
G01X45300Y-838672D02*
X45680Y-839255D01*
X46186Y-839589D01*
X46756Y-839672D01*
X47263Y-839589D01*
X47770Y-839172D01*
X48086Y-838672D01*
X48150Y-838172D01*
X48023Y-837589D01*
X47580Y-837172D01*
X47136Y-837005D01*
X46566D01*
G01X47136D02*
X47516Y-836755D01*
X47833Y-836339D01*
X47960Y-835839D01*
X47833Y-835339D01*
X47516Y-834922D01*
X46946Y-834672D01*
X46376Y-834755D01*
X45806Y-835089D01*
G01X52110Y-841339D02*
X52743Y-840505D01*
X53060Y-839672D01*
Y-836339D01*
X52743Y-835505D01*
X52110Y-834672D01*
G01X55500Y-838672D02*
X55880Y-839255D01*
X56386Y-839589D01*
X56956Y-839672D01*
X57463Y-839589D01*
X57970Y-839172D01*
X58286Y-838672D01*
X58350Y-838172D01*
X58223Y-837589D01*
X57780Y-837172D01*
X57336Y-837005D01*
X56766D01*
G01X57336D02*
X57716Y-836755D01*
X58033Y-836339D01*
X58160Y-835839D01*
X58033Y-835339D01*
X57716Y-834922D01*
X57146Y-834672D01*
X56576Y-834755D01*
X56006Y-835089D01*
G01X60790Y-835505D02*
X61170Y-835005D01*
X61613Y-834755D01*
X62120Y-834672D01*
X62753Y-834839D01*
X63196Y-835255D01*
X63323Y-835755D01*
X63260Y-836255D01*
X63006Y-836672D01*
X61740Y-837505D01*
X61170Y-838089D01*
X60790Y-838922D01*
X60663Y-839672D01*
X63323D01*
G01X66966D02*
X67093Y-838589D01*
X67283Y-837672D01*
X67536Y-836839D01*
X67853Y-835922D01*
X68360Y-834672D01*
X65826D01*
G01X71370Y-838005D02*
X73016D01*
G01X76090Y-835505D02*
X76470Y-835005D01*
X76913Y-834755D01*
X77420Y-834672D01*
X78053Y-834839D01*
X78496Y-835255D01*
X78623Y-835755D01*
X78560Y-836255D01*
X78306Y-836672D01*
X77040Y-837505D01*
X76470Y-838089D01*
X76090Y-838922D01*
X75963Y-839672D01*
X78623D01*
G01X81000Y-838672D02*
X81380Y-839255D01*
X81886Y-839589D01*
X82456Y-839672D01*
X82963Y-839589D01*
X83470Y-839172D01*
X83786Y-838672D01*
X83850Y-838172D01*
X83723Y-837589D01*
X83280Y-837172D01*
X82836Y-837005D01*
X82266D01*
G01X82836D02*
X83216Y-836755D01*
X83533Y-836339D01*
X83660Y-835839D01*
X83533Y-835339D01*
X83216Y-834922D01*
X82646Y-834672D01*
X82076Y-834755D01*
X81506Y-835089D01*
G01X88253Y-839672D02*
Y-834672D01*
X85910Y-838255D01*
X89076D01*
G01X91200Y-838922D02*
X91580Y-839339D01*
X92023Y-839589D01*
X92593Y-839672D01*
X93163Y-839505D01*
X93606Y-839172D01*
X93923Y-838589D01*
X93986Y-837922D01*
X93860Y-837255D01*
X93543Y-836839D01*
X93100Y-836505D01*
X92656Y-836422D01*
X92213Y-836505D01*
X91643Y-836839D01*
X91833Y-834672D01*
X93543D01*
G01X101590Y-839672D02*
Y-834672D01*
X103996D01*
G01X103110Y-837089D02*
X101590D01*
G01X106310Y-839672D02*
X107893Y-834672D01*
X109476Y-839672D01*
G01X108906Y-837922D02*
X106880D01*
G01X111663Y-839672D02*
X114323Y-834672D01*
G01X111663D02*
X114323Y-839672D01*
G01X118093Y-839839D02*
X117966Y-839755D01*
Y-839589D01*
X118093Y-839505D01*
X118220Y-839589D01*
Y-839755D01*
X118093Y-839839D01*
G01Y-837589D02*
X117966Y-837505D01*
Y-837339D01*
X118093Y-837255D01*
X118220Y-837339D01*
Y-837505D01*
X118093Y-837589D01*
G01X122876Y-841339D02*
X122243Y-840505D01*
X121926Y-839672D01*
Y-836339D01*
X122243Y-835505D01*
X122876Y-834672D01*
G01X128293D02*
X127786Y-834839D01*
X127406Y-835255D01*
X127153Y-835755D01*
X126963Y-836422D01*
X126900Y-837172D01*
X126963Y-837922D01*
X127153Y-838589D01*
X127406Y-839089D01*
X127786Y-839505D01*
X128293Y-839672D01*
X128800Y-839505D01*
X129180Y-839089D01*
X129433Y-838589D01*
X129623Y-837922D01*
X129686Y-837172D01*
X129623Y-836422D01*
X129433Y-835755D01*
X129180Y-835255D01*
X128800Y-834839D01*
X128293Y-834672D01*
G01X132000Y-838672D02*
X132380Y-839255D01*
X132886Y-839589D01*
X133456Y-839672D01*
X133963Y-839589D01*
X134470Y-839172D01*
X134786Y-838672D01*
X134850Y-838172D01*
X134723Y-837589D01*
X134280Y-837172D01*
X133836Y-837005D01*
X133266D01*
G01X133836D02*
X134216Y-836755D01*
X134533Y-836339D01*
X134660Y-835839D01*
X134533Y-835339D01*
X134216Y-834922D01*
X133646Y-834672D01*
X133076Y-834755D01*
X132506Y-835089D01*
G01X138810Y-841339D02*
X139443Y-840505D01*
X139760Y-839672D01*
Y-836339D01*
X139443Y-835505D01*
X138810Y-834672D01*
G01X142200Y-838672D02*
X142580Y-839255D01*
X143086Y-839589D01*
X143656Y-839672D01*
X144163Y-839589D01*
X144670Y-839172D01*
X144986Y-838672D01*
X145050Y-838172D01*
X144923Y-837589D01*
X144480Y-837172D01*
X144036Y-837005D01*
X143466D01*
G01X144036D02*
X144416Y-836755D01*
X144733Y-836339D01*
X144860Y-835839D01*
X144733Y-835339D01*
X144416Y-834922D01*
X143846Y-834672D01*
X143276Y-834755D01*
X142706Y-835089D01*
G01X147616Y-839089D02*
X148060Y-839505D01*
X148566Y-839672D01*
X149073Y-839505D01*
X149516Y-839005D01*
X149833Y-838255D01*
X149960Y-837505D01*
Y-836589D01*
X149833Y-835839D01*
X149516Y-835172D01*
X149136Y-834839D01*
X148693Y-834672D01*
X148186Y-834839D01*
X147806Y-835172D01*
X147553Y-835672D01*
X147426Y-836339D01*
X147553Y-836922D01*
X147870Y-837505D01*
X148250Y-837839D01*
X148693Y-837922D01*
X149200Y-837755D01*
X149580Y-837339D01*
X149960Y-836589D01*
G01X153666Y-839672D02*
X153793Y-838589D01*
X153983Y-837672D01*
X154236Y-836839D01*
X154553Y-835922D01*
X155060Y-834672D01*
X152526D01*
G01X158070Y-838005D02*
X159716D01*
G01X162600Y-838672D02*
X162980Y-839255D01*
X163486Y-839589D01*
X164056Y-839672D01*
X164563Y-839589D01*
X165070Y-839172D01*
X165386Y-838672D01*
X165450Y-838172D01*
X165323Y-837589D01*
X164880Y-837172D01*
X164436Y-837005D01*
X163866D01*
G01X164436D02*
X164816Y-836755D01*
X165133Y-836339D01*
X165260Y-835839D01*
X165133Y-835339D01*
X164816Y-834922D01*
X164246Y-834672D01*
X163676Y-834755D01*
X163106Y-835089D01*
G01X167890Y-837589D02*
X168333Y-837005D01*
X168713Y-836672D01*
X169220Y-836505D01*
X169663Y-836672D01*
X169980Y-837005D01*
X170233Y-837505D01*
X170296Y-838089D01*
X170233Y-838589D01*
X169980Y-839089D01*
X169600Y-839505D01*
X169156Y-839672D01*
X168650Y-839505D01*
X168206Y-839005D01*
X167953Y-838255D01*
X167890Y-837422D01*
X168016Y-836339D01*
X168206Y-835755D01*
X168523Y-835172D01*
X168966Y-834755D01*
X169410Y-834672D01*
X169853Y-834839D01*
X170170Y-835255D01*
G01X174193Y-839672D02*
Y-834672D01*
X173433Y-835672D01*
G01Y-839672D02*
X174953D01*
G01X180053D02*
Y-834672D01*
X177710Y-838255D01*
X180876D01*
G01X199093Y-769672D02*
Y-844672D01*
G01Y-819672D02*
X302093D01*
Y-794672D01*
G01X199093D02*
X302093D01*
G01X309600Y-829672D02*
Y-824672D01*
X310866D01*
X311373Y-824922D01*
X311753Y-825255D01*
X312070Y-825755D01*
X312323Y-826339D01*
X312386Y-827172D01*
X312323Y-828005D01*
X312070Y-828589D01*
X311753Y-829089D01*
X311373Y-829422D01*
X310866Y-829672D01*
X309600D01*
G01X314510D02*
X316093Y-824672D01*
X317676Y-829672D01*
G01X317106Y-827922D02*
X315080D01*
G01X321193Y-824672D02*
Y-829672D01*
G01X319736Y-824672D02*
X322650D01*
G01X327560Y-829672D02*
X325026D01*
Y-824672D01*
X327560D01*
G01X326546Y-827089D02*
X325026D01*
G01X331393Y-829839D02*
X331266Y-829755D01*
Y-829589D01*
X331393Y-829505D01*
X331520Y-829589D01*
Y-829755D01*
X331393Y-829839D01*
G01Y-827589D02*
X331266Y-827505D01*
Y-827339D01*
X331393Y-827255D01*
X331520Y-827339D01*
Y-827505D01*
X331393Y-827589D01*
G01X304093Y-769672D02*
Y-844672D01*
G01X302093Y-769672D02*
Y-844672D01*
G01X304093Y-819672D02*
X504093D01*
G01X309726Y-804672D02*
Y-799672D01*
X311246D01*
X311753Y-799922D01*
X312133Y-800505D01*
X312260Y-801172D01*
X312133Y-801839D01*
X311816Y-802339D01*
X311246Y-802589D01*
X309726D01*
G01X314953Y-804839D02*
X317233Y-799672D01*
G01X319736Y-804672D02*
Y-799672D01*
X322650Y-804672D01*
Y-799672D01*
G01X326293Y-804839D02*
X326166Y-804755D01*
Y-804589D01*
X326293Y-804505D01*
X326420Y-804589D01*
Y-804755D01*
X326293Y-804839D01*
G01Y-802589D02*
X326166Y-802505D01*
Y-802339D01*
X326293Y-802255D01*
X326420Y-802339D01*
Y-802505D01*
X326293Y-802589D01*
G01X304093Y-794672D02*
X504093D01*
G01X309726Y-779672D02*
Y-774672D01*
X311246D01*
X311753Y-774922D01*
X312133Y-775505D01*
X312260Y-776172D01*
X312133Y-776839D01*
X311816Y-777339D01*
X311246Y-777589D01*
X309726D01*
G01X314826Y-779672D02*
Y-774672D01*
X316410D01*
X316916Y-774922D01*
X317233Y-775255D01*
X317360Y-775922D01*
X317233Y-776589D01*
X316853Y-777005D01*
X316410Y-777255D01*
X314826D01*
G01X316410D02*
X317360Y-779672D01*
G01X321193D02*
X320686Y-779589D01*
X320243Y-779255D01*
X319863Y-778755D01*
X319610Y-778172D01*
X319483Y-777505D01*
Y-776839D01*
X319610Y-776172D01*
X319863Y-775589D01*
X320243Y-775089D01*
X320686Y-774755D01*
X321193Y-774672D01*
X321700Y-774755D01*
X322143Y-775089D01*
X322523Y-775589D01*
X322776Y-776172D01*
X322903Y-776839D01*
Y-777505D01*
X322776Y-778172D01*
X322523Y-778755D01*
X322143Y-779255D01*
X321700Y-779589D01*
X321193Y-779672D01*
G01X325026Y-778672D02*
X325343Y-779172D01*
X325723Y-779505D01*
X326166Y-779672D01*
X326673Y-779505D01*
X327053Y-779172D01*
X327433Y-778672D01*
X327560Y-778005D01*
Y-774672D01*
G01X332660Y-779672D02*
X330126D01*
Y-774672D01*
X332660D01*
G01X331646Y-777089D02*
X330126D01*
G01X337886Y-775089D02*
X337506Y-774839D01*
X337063Y-774672D01*
X336556D01*
X335986Y-774922D01*
X335543Y-775339D01*
X335226Y-775839D01*
X334973Y-776672D01*
X334910Y-777422D01*
X335036Y-778172D01*
X335226Y-778672D01*
X335606Y-779172D01*
X336050Y-779505D01*
X336493Y-779672D01*
X336936D01*
X337380Y-779505D01*
X337760Y-779255D01*
X338076Y-778922D01*
G01X341593Y-774672D02*
Y-779672D01*
G01X340136Y-774672D02*
X343050D01*
G01X346693Y-779839D02*
X346566Y-779755D01*
Y-779589D01*
X346693Y-779505D01*
X346820Y-779589D01*
Y-779755D01*
X346693Y-779839D01*
G01Y-777589D02*
X346566Y-777505D01*
Y-777339D01*
X346693Y-777255D01*
X346820Y-777339D01*
Y-777505D01*
X346693Y-777589D01*
G01X419093Y-819672D02*
Y-844672D01*
G01X421726Y-822172D02*
Y-827172D01*
X424260D01*
G01X427333Y-822172D02*
X428853D01*
G01X428093D02*
Y-827172D01*
G01X427333D02*
X428853D01*
G01X433700Y-824505D02*
X433953Y-824255D01*
X434143Y-823839D01*
X434270Y-823255D01*
X434143Y-822755D01*
X433890Y-822422D01*
X433446Y-822172D01*
X431736D01*
Y-827172D01*
X433826D01*
X434270Y-826839D01*
X434523Y-826339D01*
X434650Y-825755D01*
X434523Y-825172D01*
X434143Y-824672D01*
X433700Y-824505D01*
X431736D01*
G01X438293Y-827339D02*
X438166Y-827255D01*
Y-827089D01*
X438293Y-827005D01*
X438420Y-827089D01*
Y-827255D01*
X438293Y-827339D01*
G01Y-825089D02*
X438166Y-825005D01*
Y-824839D01*
X438293Y-824755D01*
X438420Y-824839D01*
Y-825005D01*
X438293Y-825089D01*
G01X470106Y-847839D02*
X470213Y-847714D01*
X470293Y-847505D01*
X470346Y-847214D01*
X470293Y-846964D01*
X470186Y-846797D01*
X470000Y-846672D01*
X469280D01*
Y-849172D01*
X470160D01*
X470346Y-849005D01*
X470453Y-848755D01*
X470506Y-848464D01*
X470453Y-848172D01*
X470293Y-847922D01*
X470106Y-847839D01*
X469280D01*
G01X472573Y-849172D02*
Y-847505D01*
G01Y-847797D02*
X472466Y-847630D01*
X472306Y-847547D01*
X472120Y-847505D01*
X471933Y-847589D01*
X471773Y-847755D01*
X471666Y-848005D01*
X471613Y-848339D01*
X471666Y-848672D01*
X471773Y-848922D01*
X471933Y-849089D01*
X472120Y-849172D01*
X472306Y-849130D01*
X472466Y-849005D01*
X472573Y-848839D01*
G01X473893Y-848880D02*
X474026Y-849047D01*
X474213Y-849172D01*
X474373D01*
X474533Y-849089D01*
X474640Y-848964D01*
X474693Y-848797D01*
X474666Y-848547D01*
X474560Y-848422D01*
X474080Y-848172D01*
X473973Y-847880D01*
X474026Y-847672D01*
X474133Y-847547D01*
X474293Y-847505D01*
X474453Y-847547D01*
X474613Y-847672D01*
G01X476093Y-848047D02*
X476946D01*
X476866Y-847755D01*
X476733Y-847589D01*
X476546Y-847505D01*
X476360Y-847547D01*
X476200Y-847672D01*
X476093Y-847964D01*
X476040Y-848214D01*
Y-848464D01*
X476093Y-848714D01*
X476226Y-848964D01*
X476386Y-849130D01*
X476573Y-849172D01*
X476760Y-849089D01*
X476946Y-848839D01*
G01X478213Y-849172D02*
Y-846672D01*
G01Y-847922D02*
X478346Y-847672D01*
X478506Y-847547D01*
X478666Y-847505D01*
X478906Y-847589D01*
X479066Y-847755D01*
X479173Y-848047D01*
Y-848380D01*
X479120Y-848714D01*
X479013Y-848964D01*
X478826Y-849130D01*
X478666Y-849172D01*
X478506Y-849130D01*
X478346Y-849005D01*
X478213Y-848797D01*
G01X480893Y-849172D02*
X480733Y-849130D01*
X480573Y-848964D01*
X480466Y-848672D01*
X480413Y-848339D01*
X480466Y-848005D01*
X480573Y-847714D01*
X480733Y-847547D01*
X480893Y-847505D01*
X481053Y-847547D01*
X481213Y-847714D01*
X481320Y-848005D01*
X481346Y-848339D01*
X481320Y-848672D01*
X481213Y-848964D01*
X481053Y-849130D01*
X480893Y-849172D01*
G01X483573D02*
Y-847505D01*
G01Y-847797D02*
X483466Y-847630D01*
X483306Y-847547D01*
X483120Y-847505D01*
X482933Y-847589D01*
X482773Y-847755D01*
X482666Y-848005D01*
X482613Y-848339D01*
X482666Y-848672D01*
X482773Y-848922D01*
X482933Y-849089D01*
X483120Y-849172D01*
X483306Y-849130D01*
X483466Y-849005D01*
X483573Y-848839D01*
G01X484920Y-849172D02*
Y-847505D01*
G01Y-847839D02*
X485053Y-847672D01*
X485186Y-847547D01*
X485373Y-847505D01*
X485506Y-847547D01*
X485666Y-847672D01*
G01X487973Y-846672D02*
Y-849172D01*
G01Y-848797D02*
X487866Y-849005D01*
X487706Y-849130D01*
X487520Y-849172D01*
X487306Y-849089D01*
X487146Y-848880D01*
X487040Y-848630D01*
X487013Y-848339D01*
X487040Y-848047D01*
X487146Y-847797D01*
X487306Y-847589D01*
X487520Y-847505D01*
X487706Y-847547D01*
X487840Y-847630D01*
X487973Y-847797D01*
G01X491360Y-849172D02*
Y-846672D01*
X492026D01*
X492240Y-846797D01*
X492373Y-846964D01*
X492426Y-847297D01*
X492373Y-847630D01*
X492213Y-847839D01*
X492026Y-847964D01*
X491360D01*
G01X492026D02*
X492426Y-849172D01*
G01X493693Y-848047D02*
X494546D01*
X494466Y-847755D01*
X494333Y-847589D01*
X494146Y-847505D01*
X493960Y-847547D01*
X493800Y-847672D01*
X493693Y-847964D01*
X493640Y-848214D01*
Y-848464D01*
X493693Y-848714D01*
X493826Y-848964D01*
X493986Y-849130D01*
X494173Y-849172D01*
X494360Y-849089D01*
X494546Y-848839D01*
G01X495813Y-847505D02*
X496293Y-849172D01*
X496773Y-847505D01*
G01X498493Y-849255D02*
X498440Y-849214D01*
Y-849130D01*
X498493Y-849089D01*
X498546Y-849130D01*
Y-849214D01*
X498493Y-849255D01*
G01X500693Y-849172D02*
X500880Y-849130D01*
X501093Y-849005D01*
X501226Y-848797D01*
X501280Y-848505D01*
X501226Y-848214D01*
X501066Y-847964D01*
X500826Y-847839D01*
X500560D01*
X500400Y-847755D01*
X500266Y-847547D01*
X500213Y-847255D01*
X500293Y-846964D01*
X500480Y-846755D01*
X500693Y-846672D01*
X500906Y-846755D01*
X501093Y-846964D01*
X501173Y-847255D01*
X501120Y-847547D01*
X500986Y-847755D01*
X500826Y-847839D01*
X500560D01*
X500320Y-847964D01*
X500160Y-848214D01*
X500106Y-848505D01*
X500160Y-848797D01*
X500293Y-849005D01*
X500506Y-849130D01*
X500693Y-849172D01*
G01X503106Y-847839D02*
X503213Y-847714D01*
X503293Y-847505D01*
X503346Y-847214D01*
X503293Y-846964D01*
X503186Y-846797D01*
X503000Y-846672D01*
X502280D01*
Y-849172D01*
X503160D01*
X503346Y-849005D01*
X503453Y-848755D01*
X503506Y-848464D01*
X503453Y-848172D01*
X503293Y-847922D01*
X503106Y-847839D01*
X502280D01*
G01X465993Y-822172D02*
Y-827172D01*
G01X464536Y-822172D02*
X467450D01*
G01X471093Y-827172D02*
X470713Y-827089D01*
X470333Y-826755D01*
X470080Y-826172D01*
X469953Y-825505D01*
X470080Y-824839D01*
X470333Y-824255D01*
X470713Y-823922D01*
X471093Y-823839D01*
X471473Y-823922D01*
X471853Y-824255D01*
X472106Y-824839D01*
X472170Y-825505D01*
X472106Y-826172D01*
X471853Y-826755D01*
X471473Y-827089D01*
X471093Y-827172D01*
G01X476193D02*
X475813Y-827089D01*
X475433Y-826755D01*
X475180Y-826172D01*
X475053Y-825505D01*
X475180Y-824839D01*
X475433Y-824255D01*
X475813Y-823922D01*
X476193Y-823839D01*
X476573Y-823922D01*
X476953Y-824255D01*
X477206Y-824839D01*
X477270Y-825505D01*
X477206Y-826172D01*
X476953Y-826755D01*
X476573Y-827089D01*
X476193Y-827172D01*
G01X481293D02*
Y-822172D01*
G01X486393Y-827339D02*
X486266Y-827255D01*
Y-827089D01*
X486393Y-827005D01*
X486520Y-827089D01*
Y-827255D01*
X486393Y-827339D01*
G01Y-825089D02*
X486266Y-825005D01*
Y-824839D01*
X486393Y-824755D01*
X486520Y-824839D01*
Y-825005D01*
X486393Y-825089D01*
G01X462093Y-819672D02*
Y-844672D01*
G01Y-794672D02*
Y-819672D01*
G01X464726Y-802172D02*
Y-797172D01*
X466310D01*
X466816Y-797422D01*
X467133Y-797755D01*
X467260Y-798422D01*
X467133Y-799089D01*
X466753Y-799505D01*
X466310Y-799755D01*
X464726D01*
G01X466310D02*
X467260Y-802172D01*
G01X472360D02*
X469826D01*
Y-797172D01*
X472360D01*
G01X471346Y-799589D02*
X469826D01*
G01X474610Y-797172D02*
X476193Y-802172D01*
X477776Y-797172D01*
G01X481293Y-802339D02*
X481166Y-802255D01*
Y-802089D01*
X481293Y-802005D01*
X481420Y-802089D01*
Y-802255D01*
X481293Y-802339D01*
G01Y-800089D02*
X481166Y-800005D01*
Y-799839D01*
X481293Y-799755D01*
X481420Y-799839D01*
Y-800005D01*
X481293Y-800089D01*
G01X-297025Y-1013390D02*
Y1828909D01*
X3691357D01*
Y-1013390D01*
X-297025D01*
G01X16913Y-817022D02*
X18480D01*
Y-818912D01*
X18010Y-819542D01*
X17461Y-819962D01*
X16678Y-820172D01*
X15895Y-819962D01*
X15346Y-819542D01*
X14876Y-818912D01*
X14563Y-818177D01*
X14406Y-817337D01*
Y-816602D01*
X14563Y-815972D01*
X14876Y-815237D01*
X15346Y-814607D01*
X15816Y-814187D01*
X16443Y-813872D01*
X16991D01*
X17618Y-814082D01*
X18088Y-814502D01*
G01X21020Y-813872D02*
Y-818387D01*
X21333Y-819332D01*
X21960Y-819962D01*
X22743Y-820172D01*
X23526Y-819962D01*
X24153Y-819332D01*
X24466Y-818387D01*
Y-813872D01*
G01X28103D02*
X29983D01*
G01X29043D02*
Y-820172D01*
G01X28103D02*
X29983D01*
G01X33698Y-819332D02*
X34325Y-819857D01*
X35030Y-820172D01*
X35656D01*
X36283Y-819857D01*
X36753Y-819332D01*
X36988Y-818597D01*
X36831Y-817862D01*
X36440Y-817232D01*
X35735Y-816812D01*
X34795Y-816602D01*
X34246Y-816182D01*
X34011Y-815447D01*
X34168Y-814712D01*
X34560Y-814187D01*
X35108Y-813872D01*
X35656D01*
X36205Y-814082D01*
X36675Y-814607D01*
G01X39998Y-820172D02*
Y-813872D01*
G01X43288D02*
Y-820172D01*
G01Y-817022D02*
X39998D01*
G01X45985Y-820172D02*
X47943Y-813872D01*
X49901Y-820172D01*
G01X49196Y-817967D02*
X46690D01*
G01X52441Y-820172D02*
Y-813872D01*
X56045Y-820172D01*
Y-813872D01*
G01X65120Y-820172D02*
Y-813872D01*
X66686D01*
X67313Y-814187D01*
X67783Y-814607D01*
X68175Y-815237D01*
X68488Y-815972D01*
X68566Y-817022D01*
X68488Y-818072D01*
X68175Y-818807D01*
X67783Y-819437D01*
X67313Y-819857D01*
X66686Y-820172D01*
X65120D01*
G01X72203Y-813872D02*
X74083D01*
G01X73143D02*
Y-820172D01*
G01X72203D02*
X74083D01*
G01X77798Y-819332D02*
X78425Y-819857D01*
X79130Y-820172D01*
X79756D01*
X80383Y-819857D01*
X80853Y-819332D01*
X81088Y-818597D01*
X80931Y-817862D01*
X80540Y-817232D01*
X79835Y-816812D01*
X78895Y-816602D01*
X78346Y-816182D01*
X78111Y-815447D01*
X78268Y-814712D01*
X78660Y-814187D01*
X79208Y-813872D01*
X79756D01*
X80305Y-814082D01*
X80775Y-814607D01*
G01X85743Y-813872D02*
Y-820172D01*
G01X83941Y-813872D02*
X87545D01*
G01X92043Y-820382D02*
X91886Y-820277D01*
Y-820067D01*
X92043Y-819962D01*
X92200Y-820067D01*
Y-820277D01*
X92043Y-820382D01*
G01X98186Y-821327D02*
X98500Y-819962D01*
G01X104643Y-813872D02*
Y-820172D01*
G01X102841Y-813872D02*
X106445D01*
G01X108985Y-820172D02*
X110943Y-813872D01*
X112901Y-820172D01*
G01X112196Y-817967D02*
X109690D01*
G01X117243Y-820172D02*
X116616Y-820067D01*
X116068Y-819647D01*
X115598Y-819017D01*
X115285Y-818282D01*
X115128Y-817442D01*
Y-816602D01*
X115285Y-815762D01*
X115598Y-815027D01*
X116068Y-814397D01*
X116616Y-813977D01*
X117243Y-813872D01*
X117870Y-813977D01*
X118418Y-814397D01*
X118888Y-815027D01*
X119201Y-815762D01*
X119358Y-816602D01*
Y-817442D01*
X119201Y-818282D01*
X118888Y-819017D01*
X118418Y-819647D01*
X117870Y-820067D01*
X117243Y-820172D01*
G01X123543D02*
Y-817337D01*
X121976Y-813872D01*
G01X125110D02*
X123543Y-817337D01*
G01X128120Y-813872D02*
Y-818387D01*
X128433Y-819332D01*
X129060Y-819962D01*
X129843Y-820172D01*
X130626Y-819962D01*
X131253Y-819332D01*
X131566Y-818387D01*
Y-813872D01*
G01X134185Y-820172D02*
X136143Y-813872D01*
X138101Y-820172D01*
G01X137396Y-817967D02*
X134890D01*
G01X140641Y-820172D02*
Y-813872D01*
X144245Y-820172D01*
Y-813872D01*
G01X18166Y-824397D02*
X17696Y-824082D01*
X17148Y-823872D01*
X16521D01*
X15816Y-824187D01*
X15268Y-824712D01*
X14876Y-825342D01*
X14563Y-826392D01*
X14485Y-827337D01*
X14641Y-828282D01*
X14876Y-828912D01*
X15346Y-829542D01*
X15895Y-829962D01*
X16443Y-830172D01*
X16991D01*
X17540Y-829962D01*
X18010Y-829647D01*
X18401Y-829227D01*
G01X21803Y-823872D02*
X23683D01*
G01X22743D02*
Y-830172D01*
G01X21803D02*
X23683D01*
G01X29043Y-823872D02*
Y-830172D01*
G01X27241Y-823872D02*
X30845D01*
G01X35343Y-830172D02*
Y-827337D01*
X33776Y-823872D01*
G01X36910D02*
X35343Y-827337D01*
G01X46220Y-828912D02*
X46690Y-829647D01*
X47316Y-830067D01*
X48021Y-830172D01*
X48648Y-830067D01*
X49275Y-829542D01*
X49666Y-828912D01*
X49745Y-828282D01*
X49588Y-827547D01*
X49040Y-827022D01*
X48491Y-826812D01*
X47786D01*
G01X48491D02*
X48961Y-826497D01*
X49353Y-825972D01*
X49510Y-825342D01*
X49353Y-824712D01*
X48961Y-824187D01*
X48256Y-823872D01*
X47551Y-823977D01*
X46846Y-824397D01*
G01X52520Y-828912D02*
X52990Y-829647D01*
X53616Y-830067D01*
X54321Y-830172D01*
X54948Y-830067D01*
X55575Y-829542D01*
X55966Y-828912D01*
X56045Y-828282D01*
X55888Y-827547D01*
X55340Y-827022D01*
X54791Y-826812D01*
X54086D01*
G01X54791D02*
X55261Y-826497D01*
X55653Y-825972D01*
X55810Y-825342D01*
X55653Y-824712D01*
X55261Y-824187D01*
X54556Y-823872D01*
X53851Y-823977D01*
X53146Y-824397D01*
G01X58820Y-828912D02*
X59290Y-829647D01*
X59916Y-830067D01*
X60621Y-830172D01*
X61248Y-830067D01*
X61875Y-829542D01*
X62266Y-828912D01*
X62345Y-828282D01*
X62188Y-827547D01*
X61640Y-827022D01*
X61091Y-826812D01*
X60386D01*
G01X61091D02*
X61561Y-826497D01*
X61953Y-825972D01*
X62110Y-825342D01*
X61953Y-824712D01*
X61561Y-824187D01*
X60856Y-823872D01*
X60151Y-823977D01*
X59446Y-824397D01*
G01X66686Y-830172D02*
X66843Y-828807D01*
X67078Y-827652D01*
X67391Y-826602D01*
X67783Y-825447D01*
X68410Y-823872D01*
X65276D01*
G01X72986Y-830172D02*
X73143Y-828807D01*
X73378Y-827652D01*
X73691Y-826602D01*
X74083Y-825447D01*
X74710Y-823872D01*
X71576D01*
G01X79286Y-831327D02*
X79600Y-829962D01*
G01X85743Y-823872D02*
Y-830172D01*
G01X83941Y-823872D02*
X87545D01*
G01X90085Y-830172D02*
X92043Y-823872D01*
X94001Y-830172D01*
G01X93296Y-827967D02*
X90790D01*
G01X97403Y-823872D02*
X99283D01*
G01X98343D02*
Y-830172D01*
G01X97403D02*
X99283D01*
G01X102293Y-823872D02*
X103390Y-830172D01*
X104643Y-823872D01*
X105896Y-830172D01*
X106993Y-823872D01*
G01X108985Y-830172D02*
X110943Y-823872D01*
X112901Y-830172D01*
G01X112196Y-827967D02*
X109690D01*
G01X115441Y-830172D02*
Y-823872D01*
X119045Y-830172D01*
Y-823872D01*
G01X129451Y-832272D02*
X128668Y-831222D01*
X128276Y-830172D01*
Y-825972D01*
X128668Y-824922D01*
X129451Y-823872D01*
G01X140876Y-830172D02*
Y-823872D01*
X142835D01*
X143461Y-824187D01*
X143853Y-824607D01*
X144010Y-825447D01*
X143853Y-826287D01*
X143383Y-826812D01*
X142835Y-827127D01*
X140876D01*
G01X142835D02*
X144010Y-830172D01*
G01X148743Y-830382D02*
X148586Y-830277D01*
Y-830067D01*
X148743Y-829962D01*
X148900Y-830067D01*
Y-830277D01*
X148743Y-830382D01*
G01X155043Y-830172D02*
X154416Y-830067D01*
X153868Y-829647D01*
X153398Y-829017D01*
X153085Y-828282D01*
X152928Y-827442D01*
Y-826602D01*
X153085Y-825762D01*
X153398Y-825027D01*
X153868Y-824397D01*
X154416Y-823977D01*
X155043Y-823872D01*
X155670Y-823977D01*
X156218Y-824397D01*
X156688Y-825027D01*
X157001Y-825762D01*
X157158Y-826602D01*
Y-827442D01*
X157001Y-828282D01*
X156688Y-829017D01*
X156218Y-829647D01*
X155670Y-830067D01*
X155043Y-830172D01*
G01X161343Y-830382D02*
X161186Y-830277D01*
Y-830067D01*
X161343Y-829962D01*
X161500Y-830067D01*
Y-830277D01*
X161343Y-830382D01*
G01X169366Y-824397D02*
X168896Y-824082D01*
X168348Y-823872D01*
X167721D01*
X167016Y-824187D01*
X166468Y-824712D01*
X166076Y-825342D01*
X165763Y-826392D01*
X165685Y-827337D01*
X165841Y-828282D01*
X166076Y-828912D01*
X166546Y-829542D01*
X167095Y-829962D01*
X167643Y-830172D01*
X168191D01*
X168740Y-829962D01*
X169210Y-829647D01*
X169601Y-829227D01*
G01X173943Y-830382D02*
X173786Y-830277D01*
Y-830067D01*
X173943Y-829962D01*
X174100Y-830067D01*
Y-830277D01*
X173943Y-830382D01*
G01X180635Y-832272D02*
X181418Y-831222D01*
X181810Y-830172D01*
Y-825972D01*
X181418Y-824922D01*
X180635Y-823872D01*
G01X38743Y-799472D02*
X36223Y-799055D01*
X34018Y-797389D01*
X32128Y-794889D01*
X30868Y-791972D01*
X30238Y-788639D01*
Y-785305D01*
X30868Y-781972D01*
X32128Y-779055D01*
X34018Y-776556D01*
X36223Y-774889D01*
X38743Y-774472D01*
X41263Y-774889D01*
X43468Y-776556D01*
X45358Y-779055D01*
X46618Y-781972D01*
X47248Y-785305D01*
Y-788639D01*
X46618Y-791972D01*
X45358Y-794889D01*
X43468Y-797389D01*
X41263Y-799055D01*
X38743Y-799472D01*
G01X41263Y-792805D02*
X45043Y-799472D01*
G01X58588Y-782806D02*
Y-794472D01*
X59848Y-797389D01*
X61738Y-799055D01*
X63943Y-799472D01*
X66148Y-799055D01*
X68038Y-797389D01*
X69298Y-794472D01*
G01Y-799472D02*
Y-782806D01*
G01X94813Y-799472D02*
Y-782806D01*
G01Y-785722D02*
X93553Y-784056D01*
X91663Y-783222D01*
X89458Y-782806D01*
X87253Y-783639D01*
X85363Y-785305D01*
X84103Y-787806D01*
X83473Y-791139D01*
X84103Y-794472D01*
X85363Y-796973D01*
X87253Y-798639D01*
X89458Y-799472D01*
X91663Y-799055D01*
X93553Y-797806D01*
X94813Y-796139D01*
G01X108988Y-799472D02*
Y-782806D01*
G01Y-786972D02*
X110248Y-784889D01*
X112138Y-783222D01*
X114658Y-782806D01*
X116863Y-783222D01*
X118753Y-784889D01*
X119698Y-787806D01*
Y-799472D01*
G01X139543Y-774472D02*
Y-799472D01*
G01X135133Y-782806D02*
X143953D01*
G01X170413Y-799472D02*
Y-782806D01*
G01Y-785722D02*
X169153Y-784056D01*
X167263Y-783222D01*
X165058Y-782806D01*
X162853Y-783639D01*
X160963Y-785305D01*
X159703Y-787806D01*
X159073Y-791139D01*
X159703Y-794472D01*
X160963Y-796973D01*
X162853Y-798639D01*
X165058Y-799472D01*
X167263Y-799055D01*
X169153Y-797806D01*
X170413Y-796139D01*
G01X14641Y-810172D02*
Y-803872D01*
X18245Y-810172D01*
Y-803872D01*
G01X22743Y-810172D02*
X22116Y-810067D01*
X21568Y-809647D01*
X21098Y-809017D01*
X20785Y-808282D01*
X20628Y-807442D01*
Y-806602D01*
X20785Y-805762D01*
X21098Y-805027D01*
X21568Y-804397D01*
X22116Y-803977D01*
X22743Y-803872D01*
X23370Y-803977D01*
X23918Y-804397D01*
X24388Y-805027D01*
X24701Y-805762D01*
X24858Y-806602D01*
Y-807442D01*
X24701Y-808282D01*
X24388Y-809017D01*
X23918Y-809647D01*
X23370Y-810067D01*
X22743Y-810172D01*
G01X29043Y-810382D02*
X28886Y-810277D01*
Y-810067D01*
X29043Y-809962D01*
X29200Y-810067D01*
Y-810277D01*
X29043Y-810382D01*
G01X33855Y-804922D02*
X34325Y-804292D01*
X34873Y-803977D01*
X35500Y-803872D01*
X36283Y-804082D01*
X36831Y-804607D01*
X36988Y-805237D01*
X36910Y-805867D01*
X36596Y-806392D01*
X35030Y-807442D01*
X34325Y-808177D01*
X33855Y-809227D01*
X33698Y-810172D01*
X36988D01*
G01X41643D02*
Y-803872D01*
X40703Y-805132D01*
G01Y-810172D02*
X42583D01*
G01X47943D02*
Y-803872D01*
X47003Y-805132D01*
G01Y-810172D02*
X48883D01*
G01X54086Y-811327D02*
X54400Y-809962D01*
G01X58193Y-803872D02*
X59290Y-810172D01*
X60543Y-803872D01*
X61796Y-810172D01*
X62893Y-803872D01*
G01X68410Y-810172D02*
X65276D01*
Y-803872D01*
X68410D01*
G01X67156Y-806917D02*
X65276D01*
G01X71341Y-810172D02*
Y-803872D01*
X74945Y-810172D01*
Y-803872D01*
G01X77798Y-810172D02*
Y-803872D01*
G01X81088D02*
Y-810172D01*
G01Y-807022D02*
X77798D01*
G01X84020Y-803872D02*
Y-808387D01*
X84333Y-809332D01*
X84960Y-809962D01*
X85743Y-810172D01*
X86526Y-809962D01*
X87153Y-809332D01*
X87466Y-808387D01*
Y-803872D01*
G01X90085Y-810172D02*
X92043Y-803872D01*
X94001Y-810172D01*
G01X93296Y-807967D02*
X90790D01*
G01X103155Y-804922D02*
X103625Y-804292D01*
X104173Y-803977D01*
X104800Y-803872D01*
X105583Y-804082D01*
X106131Y-804607D01*
X106288Y-805237D01*
X106210Y-805867D01*
X105896Y-806392D01*
X104330Y-807442D01*
X103625Y-808177D01*
X103155Y-809227D01*
X102998Y-810172D01*
X106288D01*
G01X109141D02*
Y-803872D01*
X112745Y-810172D01*
Y-803872D01*
G01X115520Y-810172D02*
Y-803872D01*
X117086D01*
X117713Y-804187D01*
X118183Y-804607D01*
X118575Y-805237D01*
X118888Y-805972D01*
X118966Y-807022D01*
X118888Y-808072D01*
X118575Y-808807D01*
X118183Y-809437D01*
X117713Y-809857D01*
X117086Y-810172D01*
X115520D01*
G01X128276D02*
Y-803872D01*
X130235D01*
X130861Y-804187D01*
X131253Y-804607D01*
X131410Y-805447D01*
X131253Y-806287D01*
X130783Y-806812D01*
X130235Y-807127D01*
X128276D01*
G01X130235D02*
X131410Y-810172D01*
G01X134420D02*
Y-803872D01*
X135986D01*
X136613Y-804187D01*
X137083Y-804607D01*
X137475Y-805237D01*
X137788Y-805972D01*
X137866Y-807022D01*
X137788Y-808072D01*
X137475Y-808807D01*
X137083Y-809437D01*
X136613Y-809857D01*
X135986Y-810172D01*
X134420D01*
G01X142443Y-810382D02*
X142286Y-810277D01*
Y-810067D01*
X142443Y-809962D01*
X142600Y-810067D01*
Y-810277D01*
X142443Y-810382D01*
G01X210093Y-779172D02*
Y-787172D01*
X214093D01*
G01X221893D02*
Y-781839D01*
G01Y-782772D02*
X221493Y-782239D01*
X220893Y-781972D01*
X220193Y-781839D01*
X219493Y-782105D01*
X218893Y-782639D01*
X218493Y-783439D01*
X218293Y-784505D01*
X218493Y-785572D01*
X218893Y-786372D01*
X219493Y-786905D01*
X220193Y-787172D01*
X220893Y-787039D01*
X221493Y-786639D01*
X221893Y-786106D01*
G01X225993Y-789572D02*
X226593Y-789839D01*
X227393Y-789572D01*
X227893Y-789039D01*
X228293Y-788372D01*
X228893Y-786239D01*
X230193Y-781839D01*
G01X226993D02*
X228893Y-786239D01*
G01X234593Y-783572D02*
X237793D01*
X237493Y-782639D01*
X236993Y-782105D01*
X236293Y-781839D01*
X235593Y-781972D01*
X234993Y-782372D01*
X234593Y-783305D01*
X234393Y-784106D01*
Y-784905D01*
X234593Y-785705D01*
X235093Y-786505D01*
X235693Y-787039D01*
X236393Y-787172D01*
X237093Y-786905D01*
X237793Y-786106D01*
G01X242693Y-787172D02*
Y-781839D01*
G01Y-782905D02*
X243193Y-782372D01*
X243693Y-781972D01*
X244393Y-781839D01*
X244893Y-781972D01*
X245493Y-782372D01*
G01X229193Y-829172D02*
X232993D01*
X229193Y-837172D01*
X232993D01*
G01X239093Y-831839D02*
Y-837172D01*
G01Y-829705D02*
X238893Y-829572D01*
Y-829305D01*
X239093Y-829172D01*
X239293Y-829305D01*
Y-829572D01*
X239093Y-829705D01*
G01X245793Y-834505D02*
X248393D01*
G01X253093Y-837172D02*
Y-829172D01*
X255493D01*
X256293Y-829572D01*
X256893Y-830505D01*
X257093Y-831572D01*
X256893Y-832639D01*
X256393Y-833439D01*
X255493Y-833839D01*
X253093D01*
G01X263093Y-831839D02*
Y-837172D01*
G01Y-829705D02*
X262893Y-829572D01*
Y-829305D01*
X263093Y-829172D01*
X263293Y-829305D01*
Y-829572D01*
X263093Y-829705D01*
G01X269393Y-837172D02*
Y-831839D01*
G01Y-833172D02*
X269793Y-832505D01*
X270393Y-831972D01*
X271193Y-831839D01*
X271893Y-831972D01*
X272493Y-832505D01*
X272793Y-833439D01*
Y-837172D01*
G01X277693Y-839172D02*
X278393Y-839705D01*
X279193Y-839839D01*
X279893Y-839705D01*
X280493Y-839039D01*
X280893Y-838105D01*
Y-831839D01*
G01Y-832905D02*
X280493Y-832372D01*
X279893Y-831972D01*
X279193Y-831839D01*
X278393Y-832105D01*
X277893Y-832639D01*
X277493Y-833572D01*
X277293Y-834505D01*
X277393Y-835305D01*
X277793Y-836239D01*
X278393Y-836905D01*
X279193Y-837172D01*
X279793Y-837039D01*
X280493Y-836505D01*
X280893Y-835972D01*
G01X239193Y-808172D02*
X241193D01*
Y-810572D01*
X240593Y-811372D01*
X239893Y-811905D01*
X238893Y-812172D01*
X237893Y-811905D01*
X237193Y-811372D01*
X236593Y-810572D01*
X236193Y-809639D01*
X235993Y-808572D01*
Y-807639D01*
X236193Y-806839D01*
X236593Y-805905D01*
X237193Y-805105D01*
X237793Y-804572D01*
X238593Y-804172D01*
X239293D01*
X240093Y-804439D01*
X240693Y-804972D01*
G01X244293Y-812172D02*
Y-804172D01*
X248893Y-812172D01*
Y-804172D01*
G01X252393Y-812172D02*
Y-804172D01*
X254393D01*
X255193Y-804572D01*
X255793Y-805105D01*
X256293Y-805905D01*
X256693Y-806839D01*
X256793Y-808172D01*
X256693Y-809505D01*
X256293Y-810439D01*
X255793Y-811239D01*
X255193Y-811772D01*
X254393Y-812172D01*
X252393D01*
G01X261693Y-780505D02*
X262293Y-779705D01*
X262993Y-779305D01*
X263793Y-779172D01*
X264793Y-779439D01*
X265493Y-780105D01*
X265693Y-780905D01*
X265593Y-781706D01*
X265193Y-782372D01*
X263193Y-783705D01*
X262293Y-784639D01*
X261693Y-785972D01*
X261493Y-787172D01*
X265693D01*
G01X336693Y-830505D02*
X337293Y-829705D01*
X337993Y-829305D01*
X338793Y-829172D01*
X339793Y-829439D01*
X340493Y-830105D01*
X340693Y-830905D01*
X340593Y-831706D01*
X340193Y-832372D01*
X338193Y-833705D01*
X337293Y-834639D01*
X336693Y-835972D01*
X336493Y-837172D01*
X340693D01*
G01X346593Y-829172D02*
X345793Y-829439D01*
X345193Y-830105D01*
X344793Y-830905D01*
X344493Y-831972D01*
X344393Y-833172D01*
X344493Y-834372D01*
X344793Y-835439D01*
X345193Y-836239D01*
X345793Y-836905D01*
X346593Y-837172D01*
X347393Y-836905D01*
X347993Y-836239D01*
X348393Y-835439D01*
X348693Y-834372D01*
X348793Y-833172D01*
X348693Y-831972D01*
X348393Y-830905D01*
X347993Y-830105D01*
X347393Y-829439D01*
X346593Y-829172D01*
G01X352693Y-830505D02*
X353293Y-829705D01*
X353993Y-829305D01*
X354793Y-829172D01*
X355793Y-829439D01*
X356493Y-830105D01*
X356693Y-830905D01*
X356593Y-831706D01*
X356193Y-832372D01*
X354193Y-833705D01*
X353293Y-834639D01*
X352693Y-835972D01*
X352493Y-837172D01*
X356693D01*
G01X360693Y-830505D02*
X361293Y-829705D01*
X361993Y-829305D01*
X362793Y-829172D01*
X363793Y-829439D01*
X364493Y-830105D01*
X364693Y-830905D01*
X364593Y-831706D01*
X364193Y-832372D01*
X362193Y-833705D01*
X361293Y-834639D01*
X360693Y-835972D01*
X360493Y-837172D01*
X364693D01*
G01X368793Y-837439D02*
X372393Y-829172D01*
G01X378593Y-837172D02*
Y-829172D01*
X377393Y-830772D01*
G01Y-837172D02*
X379793D01*
G01X384693Y-830505D02*
X385293Y-829705D01*
X385993Y-829305D01*
X386793Y-829172D01*
X387793Y-829439D01*
X388493Y-830105D01*
X388693Y-830905D01*
X388593Y-831706D01*
X388193Y-832372D01*
X386193Y-833705D01*
X385293Y-834639D01*
X384693Y-835972D01*
X384493Y-837172D01*
X388693D01*
G01X392793Y-837439D02*
X396393Y-829172D01*
G01X402593D02*
X401793Y-829439D01*
X401193Y-830105D01*
X400793Y-830905D01*
X400493Y-831972D01*
X400393Y-833172D01*
X400493Y-834372D01*
X400793Y-835439D01*
X401193Y-836239D01*
X401793Y-836905D01*
X402593Y-837172D01*
X403393Y-836905D01*
X403993Y-836239D01*
X404393Y-835439D01*
X404693Y-834372D01*
X404793Y-833172D01*
X404693Y-831972D01*
X404393Y-830905D01*
X403993Y-830105D01*
X403393Y-829439D01*
X402593Y-829172D01*
G01X408693Y-830505D02*
X409293Y-829705D01*
X409993Y-829305D01*
X410793Y-829172D01*
X411793Y-829439D01*
X412493Y-830105D01*
X412693Y-830905D01*
X412593Y-831706D01*
X412193Y-832372D01*
X410193Y-833705D01*
X409293Y-834639D01*
X408693Y-835972D01*
X408493Y-837172D01*
X412693D01*
G01X336393Y-814672D02*
Y-806672D01*
X338393D01*
X339193Y-807072D01*
X339793Y-807605D01*
X340293Y-808405D01*
X340693Y-809339D01*
X340793Y-810672D01*
X340693Y-812005D01*
X340293Y-812939D01*
X339793Y-813739D01*
X339193Y-814272D01*
X338393Y-814672D01*
X336393D01*
G01X344093D02*
X346593Y-806672D01*
X349093Y-814672D01*
G01X348193Y-811872D02*
X344993D01*
G01X354593Y-806672D02*
X353793Y-806939D01*
X353193Y-807605D01*
X352793Y-808405D01*
X352493Y-809472D01*
X352393Y-810672D01*
X352493Y-811872D01*
X352793Y-812939D01*
X353193Y-813739D01*
X353793Y-814405D01*
X354593Y-814672D01*
X355393Y-814405D01*
X355993Y-813739D01*
X356393Y-812939D01*
X356693Y-811872D01*
X356793Y-810672D01*
X356693Y-809472D01*
X356393Y-808405D01*
X355993Y-807605D01*
X355393Y-806939D01*
X354593Y-806672D01*
G01X360693Y-814672D02*
Y-806672D01*
X364493D01*
G01X363093Y-810539D02*
X360693D01*
G01X370593Y-806672D02*
X369793Y-806939D01*
X369193Y-807605D01*
X368793Y-808405D01*
X368493Y-809472D01*
X368393Y-810672D01*
X368493Y-811872D01*
X368793Y-812939D01*
X369193Y-813739D01*
X369793Y-814405D01*
X370593Y-814672D01*
X371393Y-814405D01*
X371993Y-813739D01*
X372393Y-812939D01*
X372693Y-811872D01*
X372793Y-810672D01*
X372693Y-809472D01*
X372393Y-808405D01*
X371993Y-807605D01*
X371393Y-806939D01*
X370593Y-806672D01*
G01X378593D02*
Y-814672D01*
G01X376293Y-806672D02*
X380893D01*
G01X384593Y-814672D02*
Y-806672D01*
X386993D01*
X387793Y-807072D01*
X388393Y-808005D01*
X388593Y-809072D01*
X388393Y-810139D01*
X387893Y-810939D01*
X386993Y-811339D01*
X384593D01*
G01X395393Y-810405D02*
X395793Y-810005D01*
X396093Y-809339D01*
X396293Y-808405D01*
X396093Y-807605D01*
X395693Y-807072D01*
X394993Y-806672D01*
X392293D01*
Y-814672D01*
X395593D01*
X396293Y-814139D01*
X396693Y-813339D01*
X396893Y-812405D01*
X396693Y-811472D01*
X396093Y-810672D01*
X395393Y-810405D01*
X392293D01*
G01X400093Y-814672D02*
X402593Y-806672D01*
X405093Y-814672D01*
G01X404193Y-811872D02*
X400993D01*
G01X408693Y-814672D02*
Y-806672D01*
X412493D01*
G01X411093Y-810539D02*
X408693D01*
G01X418593Y-806672D02*
X417793Y-806939D01*
X417193Y-807605D01*
X416793Y-808405D01*
X416493Y-809472D01*
X416393Y-810672D01*
X416493Y-811872D01*
X416793Y-812939D01*
X417193Y-813739D01*
X417793Y-814405D01*
X418593Y-814672D01*
X419393Y-814405D01*
X419993Y-813739D01*
X420393Y-812939D01*
X420693Y-811872D01*
X420793Y-810672D01*
X420693Y-809472D01*
X420393Y-808405D01*
X419993Y-807605D01*
X419393Y-806939D01*
X418593Y-806672D01*
G01X356693Y-787172D02*
Y-779172D01*
X360493D01*
G01X359093Y-783039D02*
X356693D01*
G01X366593Y-779172D02*
X365793Y-779439D01*
X365193Y-780105D01*
X364793Y-780905D01*
X364493Y-781972D01*
X364393Y-783172D01*
X364493Y-784372D01*
X364793Y-785439D01*
X365193Y-786239D01*
X365793Y-786905D01*
X366593Y-787172D01*
X367393Y-786905D01*
X367993Y-786239D01*
X368393Y-785439D01*
X368693Y-784372D01*
X368793Y-783172D01*
X368693Y-781972D01*
X368393Y-780905D01*
X367993Y-780105D01*
X367393Y-779439D01*
X366593Y-779172D01*
G01X374593D02*
Y-787172D01*
G01X372293Y-779172D02*
X376893D01*
G01X379593Y-789839D02*
X385593D01*
G01X388593Y-787172D02*
Y-779172D01*
X390993D01*
X391793Y-779572D01*
X392393Y-780505D01*
X392593Y-781572D01*
X392393Y-782639D01*
X391893Y-783439D01*
X390993Y-783839D01*
X388593D01*
G01X396393Y-787172D02*
Y-779172D01*
X398393D01*
X399193Y-779572D01*
X399793Y-780105D01*
X400293Y-780905D01*
X400693Y-781839D01*
X400793Y-783172D01*
X400693Y-784505D01*
X400293Y-785439D01*
X399793Y-786239D01*
X399193Y-786772D01*
X398393Y-787172D01*
X396393D01*
G01X407393Y-782905D02*
X407793Y-782505D01*
X408093Y-781839D01*
X408293Y-780905D01*
X408093Y-780105D01*
X407693Y-779572D01*
X406993Y-779172D01*
X404293D01*
Y-787172D01*
X407593D01*
X408293Y-786639D01*
X408693Y-785839D01*
X408893Y-784905D01*
X408693Y-783972D01*
X408093Y-783172D01*
X407393Y-782905D01*
X404293D01*
G01X411593Y-789839D02*
X417593D01*
G01X424793Y-779839D02*
X424193Y-779439D01*
X423493Y-779172D01*
X422693D01*
X421793Y-779572D01*
X421093Y-780239D01*
X420593Y-781039D01*
X420193Y-782372D01*
X420093Y-783572D01*
X420293Y-784772D01*
X420593Y-785572D01*
X421193Y-786372D01*
X421893Y-786905D01*
X422593Y-787172D01*
X423293D01*
X423993Y-786905D01*
X424593Y-786505D01*
X425093Y-785972D01*
G01X430593Y-787172D02*
X429793Y-787039D01*
X429093Y-786505D01*
X428493Y-785705D01*
X428093Y-784772D01*
X427893Y-783705D01*
Y-782639D01*
X428093Y-781572D01*
X428493Y-780639D01*
X429093Y-779839D01*
X429793Y-779305D01*
X430593Y-779172D01*
X431393Y-779305D01*
X432093Y-779839D01*
X432693Y-780639D01*
X433093Y-781572D01*
X433293Y-782639D01*
Y-783705D01*
X433093Y-784772D01*
X432693Y-785705D01*
X432093Y-786505D01*
X431393Y-787039D01*
X430593Y-787172D01*
G01X436293D02*
Y-779172D01*
X440893Y-787172D01*
Y-779172D01*
G01X444093D02*
X446593Y-787172D01*
X449093Y-779172D01*
G01X456593Y-787172D02*
X452593D01*
Y-779172D01*
X456593D01*
G01X454993Y-783039D02*
X452593D01*
G01X460593Y-787172D02*
Y-779172D01*
X463093D01*
X463893Y-779572D01*
X464393Y-780105D01*
X464593Y-781172D01*
X464393Y-782239D01*
X463793Y-782905D01*
X463093Y-783305D01*
X460593D01*
G01X463093D02*
X464593Y-787172D01*
G01X470593Y-779172D02*
Y-787172D01*
G01X468293Y-779172D02*
X472893D01*
G01X480593Y-787172D02*
X476593D01*
Y-779172D01*
X480593D01*
G01X478993Y-783039D02*
X476593D01*
G01X484593Y-787172D02*
Y-779172D01*
X487093D01*
X487893Y-779572D01*
X488393Y-780105D01*
X488593Y-781172D01*
X488393Y-782239D01*
X487793Y-782905D01*
X487093Y-783305D01*
X484593D01*
G01X487093D02*
X488593Y-787172D01*
G01X425093Y-840172D02*
Y-832172D01*
X423893Y-833772D01*
G01Y-840172D02*
X426293D01*
G01X431193Y-836839D02*
X431893Y-835905D01*
X432493Y-835372D01*
X433293Y-835105D01*
X433993Y-835372D01*
X434493Y-835905D01*
X434893Y-836705D01*
X434993Y-837639D01*
X434893Y-838439D01*
X434493Y-839239D01*
X433893Y-839905D01*
X433193Y-840172D01*
X432393Y-839905D01*
X431693Y-839106D01*
X431293Y-837905D01*
X431193Y-836572D01*
X431393Y-834839D01*
X431693Y-833905D01*
X432193Y-832972D01*
X432893Y-832305D01*
X433593Y-832172D01*
X434293Y-832439D01*
X434793Y-833105D01*
G01X441093Y-840439D02*
X440893Y-840305D01*
Y-840039D01*
X441093Y-839905D01*
X441293Y-840039D01*
Y-840305D01*
X441093Y-840439D01*
G01X447193Y-836839D02*
X447893Y-835905D01*
X448493Y-835372D01*
X449293Y-835105D01*
X449993Y-835372D01*
X450493Y-835905D01*
X450893Y-836705D01*
X450993Y-837639D01*
X450893Y-838439D01*
X450493Y-839239D01*
X449893Y-839905D01*
X449193Y-840172D01*
X448393Y-839905D01*
X447693Y-839106D01*
X447293Y-837905D01*
X447193Y-836572D01*
X447393Y-834839D01*
X447693Y-833905D01*
X448193Y-832972D01*
X448893Y-832305D01*
X449593Y-832172D01*
X450293Y-832439D01*
X450793Y-833105D01*
G01X470093Y-840172D02*
Y-832172D01*
X468893Y-833772D01*
G01Y-840172D02*
X471293D01*
G01X477893D02*
X478093Y-838439D01*
X478393Y-836972D01*
X478793Y-835639D01*
X479293Y-834172D01*
X480093Y-832172D01*
X476093D01*
G01X486093Y-840439D02*
X485893Y-840305D01*
Y-840039D01*
X486093Y-839905D01*
X486293Y-840039D01*
Y-840305D01*
X486093Y-840439D01*
G01X492193Y-833505D02*
X492793Y-832705D01*
X493493Y-832305D01*
X494293Y-832172D01*
X495293Y-832439D01*
X495993Y-833105D01*
X496193Y-833905D01*
X496093Y-834706D01*
X495693Y-835372D01*
X493693Y-836705D01*
X492793Y-837639D01*
X492193Y-838972D01*
X491993Y-840172D01*
X496193D01*
G01X490193Y-815172D02*
Y-807172D01*
X493993D01*
G01X492593Y-811039D02*
X490193D01*
G54D49*
G01X927000Y361075D02*
Y363854D01*
M02*
